(kicad_sch (version 20230121) (generator eeschema)

  (paper "A3")

  (title_block
    (title "ECP5 - Datacenter Secure Control Module (DC-SCM)")
    (date "2024-07-15")
    (rev "1.2.1")
  )

  (junction (at 114.3 29.21) (diameter 0) (color 0 0 0 0)
  )
  (junction (at 363.22 35.56) (diameter 0) (color 0 0 0 0)
  )
  (junction (at 391.16 27.94) (diameter 0) (color 0 0 0 0)
  )
  (junction (at 227.33 36.83) (diameter 0) (color 0 0 0 0)
  )
  (junction (at 167.64 36.83) (diameter 0) (color 0 0 0 0)
  )
  (junction (at 52.07 264.16) (diameter 0) (color 0 0 0 0)
  )
  (junction (at 104.14 29.21) (diameter 0) (color 0 0 0 0)
  )
  (junction (at 227.33 29.21) (diameter 0) (color 0 0 0 0)
  )
  (junction (at 238.76 36.83) (diameter 0) (color 0 0 0 0)
  )
  (junction (at 381 27.94) (diameter 0) (color 0 0 0 0)
  )
  (junction (at 109.22 186.69) (diameter 0) (color 0 0 0 0)
  )
  (junction (at 59.69 36.83) (diameter 0) (color 0 0 0 0)
  )
  (junction (at 27.94 247.65) (diameter 0) (color 0 0 0 0)
  )
  (junction (at 250.19 29.21) (diameter 0) (color 0 0 0 0)
  )
  (junction (at 26.67 29.21) (diameter 0) (color 0 0 0 0)
  )
  (junction (at 353.06 27.94) (diameter 0) (color 0 0 0 0)
  )
  (junction (at 157.48 36.83) (diameter 0) (color 0 0 0 0)
  )
  (junction (at 177.8 36.83) (diameter 0) (color 0 0 0 0)
  )
  (junction (at 177.8 29.21) (diameter 0) (color 0 0 0 0)
  )
  (junction (at 187.96 29.21) (diameter 0) (color 0 0 0 0)
  )
  (junction (at 278.13 91.44) (diameter 0) (color 0 0 0 0)
  )
  (junction (at 93.98 36.83) (diameter 0) (color 0 0 0 0)
  )
  (junction (at 331.47 29.21) (diameter 0) (color 0 0 0 0)
  )
  (junction (at 353.06 35.56) (diameter 0) (color 0 0 0 0)
  )
  (junction (at 171.45 190.5) (diameter 0) (color 0 0 0 0)
  )
  (junction (at 48.26 29.21) (diameter 0) (color 0 0 0 0)
  )
  (junction (at 97.79 194.31) (diameter 0) (color 0 0 0 0)
  )
  (junction (at 299.72 29.21) (diameter 0) (color 0 0 0 0)
  )
  (junction (at 260.35 29.21) (diameter 0) (color 0 0 0 0)
  )
  (junction (at 38.1 29.21) (diameter 0) (color 0 0 0 0)
  )
  (junction (at 250.19 36.83) (diameter 0) (color 0 0 0 0)
  )
  (junction (at 157.48 198.12) (diameter 0) (color 0 0 0 0)
  )
  (junction (at 104.14 36.83) (diameter 0) (color 0 0 0 0)
  )
  (junction (at 187.96 36.83) (diameter 0) (color 0 0 0 0)
  )
  (junction (at 125.73 29.21) (diameter 0) (color 0 0 0 0)
  )
  (junction (at 48.26 36.83) (diameter 0) (color 0 0 0 0)
  )
  (junction (at 288.29 29.21) (diameter 0) (color 0 0 0 0)
  )
  (junction (at 26.67 232.41) (diameter 0) (color 0 0 0 0)
  )
  (junction (at 309.88 29.21) (diameter 0) (color 0 0 0 0)
  )
  (junction (at 25.4 262.89) (diameter 0) (color 0 0 0 0)
  )
  (junction (at 59.69 29.21) (diameter 0) (color 0 0 0 0)
  )
  (junction (at 372.11 27.94) (diameter 0) (color 0 0 0 0)
  )
  (junction (at 309.88 36.83) (diameter 0) (color 0 0 0 0)
  )
  (junction (at 93.98 29.21) (diameter 0) (color 0 0 0 0)
  )
  (junction (at 157.48 190.5) (diameter 0) (color 0 0 0 0)
  )
  (junction (at 69.85 29.21) (diameter 0) (color 0 0 0 0)
  )
  (junction (at 321.31 36.83) (diameter 0) (color 0 0 0 0)
  )
  (junction (at 381 35.56) (diameter 0) (color 0 0 0 0)
  )
  (junction (at 38.1 36.83) (diameter 0) (color 0 0 0 0)
  )
  (junction (at 363.22 27.94) (diameter 0) (color 0 0 0 0)
  )
  (junction (at 167.64 29.21) (diameter 0) (color 0 0 0 0)
  )
  (junction (at 26.67 36.83) (diameter 0) (color 0 0 0 0)
  )
  (junction (at 273.05 91.44) (diameter 0) (color 0 0 0 0)
  )
  (junction (at 238.76 29.21) (diameter 0) (color 0 0 0 0)
  )
  (junction (at 125.73 36.83) (diameter 0) (color 0 0 0 0)
  )
  (junction (at 299.72 36.83) (diameter 0) (color 0 0 0 0)
  )
  (junction (at 288.29 36.83) (diameter 0) (color 0 0 0 0)
  )
  (junction (at 41.91 207.01) (diameter 0) (color 0 0 0 0)
  )
  (junction (at 198.12 29.21) (diameter 0) (color 0 0 0 0)
  )
  (junction (at 157.48 29.21) (diameter 0) (color 0 0 0 0)
  )
  (junction (at 52.07 276.86) (diameter 0) (color 0 0 0 0)
  )
  (junction (at 372.11 35.56) (diameter 0) (color 0 0 0 0)
  )
  (junction (at 321.31 29.21) (diameter 0) (color 0 0 0 0)
  )
  (junction (at 135.89 29.21) (diameter 0) (color 0 0 0 0)
  )
  (junction (at 370.84 232.41) (diameter 0) (color 0 0 0 0)
  )
  (junction (at 97.79 186.69) (diameter 0) (color 0 0 0 0)
  )
  (junction (at 114.3 36.83) (diameter 0) (color 0 0 0 0)
  )
  (junction (at 48.26 264.16) (diameter 0) (color 0 0 0 0)
  )

  (no_connect (at 48.26 123.19))
  (no_connect (at 238.76 77.47))
  (no_connect (at 238.76 102.87))
  (no_connect (at 111.76 173.99))
  (no_connect (at 238.76 105.41))
  (no_connect (at 175.26 57.15))
  (no_connect (at 48.26 138.43))
  (no_connect (at 266.7 246.38))
  (no_connect (at 48.26 113.03))
  (no_connect (at 48.26 140.97))
  (no_connect (at 175.26 158.75))
  (no_connect (at 48.26 110.49))
  (no_connect (at 175.26 161.29))
  (no_connect (at 266.7 256.54))
  (no_connect (at 48.26 151.13))
  (no_connect (at 151.13 243.84))
  (no_connect (at 238.76 123.19))
  (no_connect (at 238.76 168.91))
  (no_connect (at 48.26 168.91))
  (no_connect (at 238.76 209.55))
  (no_connect (at 175.26 72.39))
  (no_connect (at 175.26 100.33))
  (no_connect (at 238.76 118.11))
  (no_connect (at 367.03 60.96))
  (no_connect (at 303.53 104.14))
  (no_connect (at 175.26 176.53))
  (no_connect (at 367.03 119.38))
  (no_connect (at 48.26 128.27))
  (no_connect (at 367.03 134.62))
  (no_connect (at 111.76 171.45))
  (no_connect (at 238.76 92.71))
  (no_connect (at 303.53 99.06))
  (no_connect (at 151.13 264.16))
  (no_connect (at 175.26 123.19))
  (no_connect (at 175.26 87.63))
  (no_connect (at 236.22 265.43))
  (no_connect (at 367.03 58.42))
  (no_connect (at 48.26 82.55))
  (no_connect (at 175.26 92.71))
  (no_connect (at 175.26 156.21))
  (no_connect (at 175.26 143.51))
  (no_connect (at 48.26 148.59))
  (no_connect (at 48.26 191.77))
  (no_connect (at 266.7 248.92))
  (no_connect (at 175.26 62.23))
  (no_connect (at 151.13 266.7))
  (no_connect (at 236.22 267.97))
  (no_connect (at 238.76 97.79))
  (no_connect (at 367.03 106.68))
  (no_connect (at 367.03 78.74))
  (no_connect (at 175.26 74.93))
  (no_connect (at 175.26 69.85))
  (no_connect (at 48.26 173.99))
  (no_connect (at 367.03 121.92))
  (no_connect (at 367.03 104.14))
  (no_connect (at 175.26 130.81))
  (no_connect (at 367.03 66.04))
  (no_connect (at 238.76 113.03))
  (no_connect (at 48.26 80.01))
  (no_connect (at 236.22 273.05))
  (no_connect (at 151.13 241.3))
  (no_connect (at 367.03 55.88))
  (no_connect (at 48.26 97.79))
  (no_connect (at 175.26 77.47))
  (no_connect (at 48.26 102.87))
  (no_connect (at 48.26 85.09))
  (no_connect (at 367.03 165.1))
  (no_connect (at 175.26 64.77))
  (no_connect (at 367.03 127))
  (no_connect (at 175.26 171.45))
  (no_connect (at 367.03 63.5))
  (no_connect (at 236.22 270.51))
  (no_connect (at 111.76 161.29))
  (no_connect (at 48.26 125.73))
  (no_connect (at 175.26 95.25))
  (no_connect (at 175.26 146.05))
  (no_connect (at 48.26 115.57))
  (no_connect (at 175.26 163.83))
  (no_connect (at 48.26 143.51))
  (no_connect (at 48.26 92.71))
  (no_connect (at 303.53 129.54))
  (no_connect (at 238.76 82.55))
  (no_connect (at 303.53 132.08))
  (no_connect (at 48.26 196.85))
  (no_connect (at 266.7 259.08))
  (no_connect (at 48.26 105.41))
  (no_connect (at 266.7 238.76))
  (no_connect (at 266.7 243.84))
  (no_connect (at 238.76 179.07))
  (no_connect (at 48.26 135.89))
  (no_connect (at 238.76 120.65))
  (no_connect (at 266.7 236.22))
  (no_connect (at 175.26 133.35))
  (no_connect (at 266.7 241.3))
  (no_connect (at 48.26 153.67))
  (no_connect (at 175.26 166.37))
  (no_connect (at 175.26 138.43))
  (no_connect (at 367.03 86.36))
  (no_connect (at 175.26 173.99))
  (no_connect (at 175.26 85.09))
  (no_connect (at 48.26 176.53))
  (no_connect (at 111.76 168.91))
  (no_connect (at 48.26 171.45))
  (no_connect (at 175.26 90.17))
  (no_connect (at 151.13 261.62))
  (no_connect (at 367.03 129.54))
  (no_connect (at 303.53 114.3))
  (no_connect (at 238.76 107.95))
  (no_connect (at 303.53 134.62))
  (no_connect (at 238.76 158.75))
  (no_connect (at 238.76 212.09))
  (no_connect (at 48.26 107.95))
  (no_connect (at 175.26 82.55))
  (no_connect (at 266.7 254))
  (no_connect (at 303.53 111.76))
  (no_connect (at 48.26 100.33))
  (no_connect (at 48.26 120.65))
  (no_connect (at 175.26 148.59))
  (no_connect (at 238.76 173.99))
  (no_connect (at 303.53 119.38))
  (no_connect (at 238.76 135.89))
  (no_connect (at 367.03 142.24))
  (no_connect (at 303.53 109.22))
  (no_connect (at 238.76 184.15))
  (no_connect (at 367.03 137.16))
  (no_connect (at 367.03 109.22))
  (no_connect (at 238.76 100.33))
  (no_connect (at 367.03 124.46))
  (no_connect (at 48.26 184.15))
  (no_connect (at 367.03 73.66))
  (no_connect (at 175.26 102.87))
  (no_connect (at 175.26 140.97))
  (no_connect (at 175.26 67.31))
  (no_connect (at 48.26 146.05))
  (no_connect (at 48.26 156.21))
  (no_connect (at 175.26 153.67))
  (no_connect (at 367.03 111.76))
  (no_connect (at 367.03 175.26))
  (no_connect (at 48.26 179.07))
  (no_connect (at 367.03 116.84))
  (no_connect (at 238.76 74.93))
  (no_connect (at 175.26 97.79))
  (no_connect (at 175.26 59.69))
  (no_connect (at 48.26 95.25))
  (no_connect (at 303.53 127))
  (no_connect (at 48.26 133.35))
  (no_connect (at 48.26 118.11))
  (no_connect (at 238.76 128.27))
  (no_connect (at 303.53 101.6))
  (no_connect (at 367.03 68.58))
  (no_connect (at 367.03 172.72))
  (no_connect (at 175.26 80.01))
  (no_connect (at 175.26 151.13))
  (no_connect (at 48.26 130.81))
  (no_connect (at 238.76 87.63))
  (no_connect (at 175.26 135.89))
  (no_connect (at 367.03 114.3))
  (no_connect (at 303.53 124.46))
  (no_connect (at 111.76 176.53))
  (no_connect (at 367.03 71.12))
  (no_connect (at 303.53 96.52))
  (no_connect (at 266.7 251.46))
  (no_connect (at 303.53 106.68))

  (wire (pts (xy 278.13 99.06) (xy 278.13 100.33))
    (stroke (width 0) (type default))
  )
  (wire (pts (xy 208.28 29.21) (xy 208.28 57.15))
    (stroke (width 0) (type default))
  )
  (wire (pts (xy 166.37 128.27) (xy 175.26 128.27))
    (stroke (width 0) (type default))
  )
  (wire (pts (xy 294.64 200.66) (xy 303.53 200.66))
    (stroke (width 0) (type default))
  )
  (wire (pts (xy 294.64 182.88) (xy 303.53 182.88))
    (stroke (width 0) (type default))
  )
  (wire (pts (xy 238.76 163.83) (xy 233.68 163.83))
    (stroke (width 0) (type default))
  )
  (wire (pts (xy 86.36 269.24) (xy 93.98 269.24))
    (stroke (width 0) (type default))
  )
  (wire (pts (xy 372.11 34.29) (xy 372.11 35.56))
    (stroke (width 0) (type default))
  )
  (wire (pts (xy 294.64 139.7) (xy 303.53 139.7))
    (stroke (width 0) (type default))
  )
  (wire (pts (xy 93.98 233.68) (xy 86.36 233.68))
    (stroke (width 0) (type default))
  )
  (wire (pts (xy 177.8 29.21) (xy 177.8 30.48))
    (stroke (width 0) (type default))
  )
  (wire (pts (xy 157.48 29.21) (xy 167.64 29.21))
    (stroke (width 0) (type default))
  )
  (wire (pts (xy 86.36 264.16) (xy 93.98 264.16))
    (stroke (width 0) (type default))
  )
  (wire (pts (xy 372.11 35.56) (xy 381 35.56))
    (stroke (width 0) (type default))
  )
  (wire (pts (xy 367.03 149.86) (xy 353.06 149.86))
    (stroke (width 0) (type default))
  )
  (wire (pts (xy 104.14 143.51) (xy 111.76 143.51))
    (stroke (width 0) (type default))
  )
  (wire (pts (xy 26.67 36.83) (xy 26.67 40.64))
    (stroke (width 0) (type default))
  )
  (wire (pts (xy 176.53 218.44) (xy 182.88 218.44))
    (stroke (width 0) (type default))
  )
  (wire (pts (xy 48.26 273.05) (xy 48.26 276.86))
    (stroke (width 0) (type default))
  )
  (wire (pts (xy 102.87 113.03) (xy 111.76 113.03))
    (stroke (width 0) (type default))
  )
  (wire (pts (xy 238.76 110.49) (xy 224.79 110.49))
    (stroke (width 0) (type default))
  )
  (wire (pts (xy 346.71 231.14) (xy 346.71 232.41))
    (stroke (width 0) (type default))
  )
  (polyline (pts (xy 436.88 228.6) (xy 539.75 228.6))
    (stroke (width 0) (type dash))
  )

  (wire (pts (xy 102.87 123.19) (xy 111.76 123.19))
    (stroke (width 0) (type default))
  )
  (wire (pts (xy 331.47 29.21) (xy 331.47 30.48))
    (stroke (width 0) (type default))
  )
  (polyline (pts (xy 165.1 243.84) (xy 163.83 243.84))
    (stroke (width 0) (type dash))
  )

  (wire (pts (xy 86.36 266.7) (xy 93.98 266.7))
    (stroke (width 0) (type default))
  )
  (wire (pts (xy 48.26 74.93) (xy 39.37 74.93))
    (stroke (width 0) (type default))
  )
  (wire (pts (xy 238.76 214.63) (xy 233.68 214.63))
    (stroke (width 0) (type default))
  )
  (wire (pts (xy 135.89 226.06) (xy 142.24 226.06))
    (stroke (width 0) (type default))
  )
  (wire (pts (xy 198.12 29.21) (xy 198.12 30.48))
    (stroke (width 0) (type default))
  )
  (wire (pts (xy 370.84 237.49) (xy 372.11 237.49))
    (stroke (width 0) (type default))
  )
  (wire (pts (xy 125.73 29.21) (xy 135.89 29.21))
    (stroke (width 0) (type default))
  )
  (wire (pts (xy 104.14 29.21) (xy 114.3 29.21))
    (stroke (width 0) (type default))
  )
  (wire (pts (xy 102.87 130.81) (xy 111.76 130.81))
    (stroke (width 0) (type default))
  )
  (wire (pts (xy 391.16 232.41) (xy 392.43 232.41))
    (stroke (width 0) (type default))
  )
  (wire (pts (xy 294.64 187.96) (xy 303.53 187.96))
    (stroke (width 0) (type default))
  )
  (wire (pts (xy 321.31 29.21) (xy 321.31 30.48))
    (stroke (width 0) (type default))
  )
  (bus (pts (xy 251.46 115.57) (xy 254 115.57))
    (stroke (width 0) (type default))
  )

  (wire (pts (xy 111.76 92.71) (xy 102.87 92.71))
    (stroke (width 0) (type default))
  )
  (wire (pts (xy 294.64 215.9) (xy 303.53 215.9))
    (stroke (width 0) (type default))
  )
  (wire (pts (xy 294.64 55.88) (xy 303.53 55.88))
    (stroke (width 0) (type default))
  )
  (wire (pts (xy 288.29 29.21) (xy 299.72 29.21))
    (stroke (width 0) (type default))
  )
  (wire (pts (xy 97.79 166.37) (xy 111.76 166.37))
    (stroke (width 0) (type default))
  )
  (wire (pts (xy 142.24 223.52) (xy 135.89 223.52))
    (stroke (width 0) (type default))
  )
  (wire (pts (xy 111.76 97.79) (xy 102.87 97.79))
    (stroke (width 0) (type default))
  )
  (wire (pts (xy 111.76 95.25) (xy 102.87 95.25))
    (stroke (width 0) (type default))
  )
  (wire (pts (xy 309.88 29.21) (xy 321.31 29.21))
    (stroke (width 0) (type default))
  )
  (wire (pts (xy 111.76 135.89) (xy 102.87 135.89))
    (stroke (width 0) (type default))
  )
  (wire (pts (xy 97.79 163.83) (xy 111.76 163.83))
    (stroke (width 0) (type default))
  )
  (wire (pts (xy 38.1 35.56) (xy 38.1 36.83))
    (stroke (width 0) (type default))
  )
  (wire (pts (xy 294.64 71.12) (xy 303.53 71.12))
    (stroke (width 0) (type default))
  )
  (wire (pts (xy 273.05 99.06) (xy 273.05 100.33))
    (stroke (width 0) (type default))
  )
  (wire (pts (xy 294.64 170.18) (xy 303.53 170.18))
    (stroke (width 0) (type default))
  )
  (wire (pts (xy 48.26 72.39) (xy 39.37 72.39))
    (stroke (width 0) (type default))
  )
  (wire (pts (xy 353.06 154.94) (xy 367.03 154.94))
    (stroke (width 0) (type default))
  )
  (bus (pts (xy 254 196.85) (xy 254 191.77))
    (stroke (width 0) (type default))
  )

  (wire (pts (xy 370.84 237.49) (xy 370.84 240.03))
    (stroke (width 0) (type default))
  )
  (wire (pts (xy 93.98 223.52) (xy 86.36 223.52))
    (stroke (width 0) (type default))
  )
  (wire (pts (xy 346.71 237.49) (xy 346.71 238.76))
    (stroke (width 0) (type default))
  )
  (wire (pts (xy 26.67 207.01) (xy 41.91 207.01))
    (stroke (width 0) (type default))
  )
  (polyline (pts (xy 436.88 142.24) (xy 539.75 142.24))
    (stroke (width 0) (type dash))
  )

  (wire (pts (xy 104.14 146.05) (xy 111.76 146.05))
    (stroke (width 0) (type default))
  )
  (wire (pts (xy 86.36 254) (xy 93.98 254))
    (stroke (width 0) (type default))
  )
  (wire (pts (xy 104.14 138.43) (xy 111.76 138.43))
    (stroke (width 0) (type default))
  )
  (wire (pts (xy 114.3 29.21) (xy 125.73 29.21))
    (stroke (width 0) (type default))
  )
  (wire (pts (xy 361.95 96.52) (xy 367.03 96.52))
    (stroke (width 0) (type default))
  )
  (wire (pts (xy 166.37 107.95) (xy 175.26 107.95))
    (stroke (width 0) (type default))
  )
  (wire (pts (xy 361.95 91.44) (xy 367.03 91.44))
    (stroke (width 0) (type default))
  )
  (wire (pts (xy 363.22 27.94) (xy 372.11 27.94))
    (stroke (width 0) (type default))
  )
  (wire (pts (xy 294.64 154.94) (xy 303.53 154.94))
    (stroke (width 0) (type default))
  )
  (wire (pts (xy 48.26 57.15) (xy 39.37 57.15))
    (stroke (width 0) (type default))
  )
  (wire (pts (xy 351.79 27.94) (xy 353.06 27.94))
    (stroke (width 0) (type default))
  )
  (polyline (pts (xy 436.88 130.81) (xy 539.75 130.81))
    (stroke (width 0) (type dash))
  )

  (wire (pts (xy 370.84 232.41) (xy 372.11 232.41))
    (stroke (width 0) (type default))
  )
  (wire (pts (xy 299.72 35.56) (xy 299.72 36.83))
    (stroke (width 0) (type default))
  )
  (wire (pts (xy 48.26 69.85) (xy 39.37 69.85))
    (stroke (width 0) (type default))
  )
  (wire (pts (xy 147.32 226.06) (xy 151.13 226.06))
    (stroke (width 0) (type default))
  )
  (wire (pts (xy 353.06 35.56) (xy 363.22 35.56))
    (stroke (width 0) (type default))
  )
  (wire (pts (xy 21.59 262.89) (xy 25.4 262.89))
    (stroke (width 0) (type default))
  )
  (wire (pts (xy 86.36 213.36) (xy 93.98 213.36))
    (stroke (width 0) (type default))
  )
  (bus (pts (xy 243.84 96.52) (xy 261.62 96.52))
    (stroke (width 0) (type default))
  )

  (wire (pts (xy 111.76 82.55) (xy 102.87 82.55))
    (stroke (width 0) (type default))
  )
  (wire (pts (xy 288.29 35.56) (xy 288.29 36.83))
    (stroke (width 0) (type default))
  )
  (wire (pts (xy 135.89 231.14) (xy 151.13 231.14))
    (stroke (width 0) (type default))
  )
  (wire (pts (xy 238.76 199.39) (xy 224.79 199.39))
    (stroke (width 0) (type default))
  )
  (wire (pts (xy 238.76 148.59) (xy 233.68 148.59))
    (stroke (width 0) (type default))
  )
  (bus (pts (xy 254 115.57) (xy 254 110.49))
    (stroke (width 0) (type default))
  )

  (wire (pts (xy 294.64 198.12) (xy 303.53 198.12))
    (stroke (width 0) (type default))
  )
  (wire (pts (xy 391.16 34.29) (xy 391.16 35.56))
    (stroke (width 0) (type default))
  )
  (wire (pts (xy 151.13 233.68) (xy 135.89 233.68))
    (stroke (width 0) (type default))
  )
  (wire (pts (xy 284.48 29.21) (xy 288.29 29.21))
    (stroke (width 0) (type default))
  )
  (wire (pts (xy 250.19 35.56) (xy 250.19 36.83))
    (stroke (width 0) (type default))
  )
  (wire (pts (xy 26.67 232.41) (xy 29.21 232.41))
    (stroke (width 0) (type default))
  )
  (wire (pts (xy 25.4 247.65) (xy 27.94 247.65))
    (stroke (width 0) (type default))
  )
  (polyline (pts (xy 436.88 153.67) (xy 539.75 153.67))
    (stroke (width 0) (type dash))
  )
  (polyline (pts (xy 156.21 246.38) (xy 157.48 246.38))
    (stroke (width 0) (type dash))
  )

  (bus (pts (xy 254 151.13) (xy 254 156.21))
    (stroke (width 0) (type default))
  )

  (wire (pts (xy 111.76 133.35) (xy 102.87 133.35))
    (stroke (width 0) (type default))
  )
  (wire (pts (xy 361.95 83.82) (xy 367.03 83.82))
    (stroke (width 0) (type default))
  )
  (polyline (pts (xy 483.87 130.81) (xy 483.87 228.6))
    (stroke (width 0) (type dash))
  )

  (wire (pts (xy 321.31 35.56) (xy 321.31 36.83))
    (stroke (width 0) (type default))
  )
  (wire (pts (xy 86.36 256.54) (xy 93.98 256.54))
    (stroke (width 0) (type default))
  )
  (bus (pts (xy 251.46 196.85) (xy 254 196.85))
    (stroke (width 0) (type default))
  )

  (wire (pts (xy 294.64 193.04) (xy 303.53 193.04))
    (stroke (width 0) (type default))
  )
  (bus (pts (xy 254 156.21) (xy 251.46 156.21))
    (stroke (width 0) (type default))
  )

  (wire (pts (xy 111.76 62.23) (xy 102.87 62.23))
    (stroke (width 0) (type default))
  )
  (wire (pts (xy 224.79 204.47) (xy 238.76 204.47))
    (stroke (width 0) (type default))
  )
  (wire (pts (xy 201.93 255.27) (xy 208.28 255.27))
    (stroke (width 0) (type default))
  )
  (wire (pts (xy 25.4 255.27) (xy 25.4 262.89))
    (stroke (width 0) (type default))
  )
  (wire (pts (xy 177.8 29.21) (xy 187.96 29.21))
    (stroke (width 0) (type default))
  )
  (wire (pts (xy 157.48 191.77) (xy 157.48 190.5))
    (stroke (width 0) (type default))
  )
  (wire (pts (xy 135.89 238.76) (xy 151.13 238.76))
    (stroke (width 0) (type default))
  )
  (wire (pts (xy 250.19 29.21) (xy 260.35 29.21))
    (stroke (width 0) (type default))
  )
  (wire (pts (xy 321.31 29.21) (xy 331.47 29.21))
    (stroke (width 0) (type default))
  )
  (wire (pts (xy 93.98 36.83) (xy 93.98 40.64))
    (stroke (width 0) (type default))
  )
  (wire (pts (xy 294.64 88.9) (xy 303.53 88.9))
    (stroke (width 0) (type default))
  )
  (wire (pts (xy 24.13 29.21) (xy 26.67 29.21))
    (stroke (width 0) (type default))
  )
  (wire (pts (xy 104.14 140.97) (xy 111.76 140.97))
    (stroke (width 0) (type default))
  )
  (polyline (pts (xy 436.88 124.46) (xy 539.75 124.46))
    (stroke (width 0) (type dash))
  )

  (wire (pts (xy 260.35 29.21) (xy 260.35 30.48))
    (stroke (width 0) (type default))
  )
  (wire (pts (xy 38.1 36.83) (xy 48.26 36.83))
    (stroke (width 0) (type default))
  )
  (wire (pts (xy 353.06 162.56) (xy 367.03 162.56))
    (stroke (width 0) (type default))
  )
  (wire (pts (xy 361.95 76.2) (xy 367.03 76.2))
    (stroke (width 0) (type default))
  )
  (wire (pts (xy 353.06 160.02) (xy 367.03 160.02))
    (stroke (width 0) (type default))
  )
  (wire (pts (xy 111.76 74.93) (xy 102.87 74.93))
    (stroke (width 0) (type default))
  )
  (wire (pts (xy 111.76 59.69) (xy 102.87 59.69))
    (stroke (width 0) (type default))
  )
  (wire (pts (xy 48.26 252.73) (xy 46.99 252.73))
    (stroke (width 0) (type default))
  )
  (wire (pts (xy 59.69 36.83) (xy 69.85 36.83))
    (stroke (width 0) (type default))
  )
  (wire (pts (xy 294.64 185.42) (xy 303.53 185.42))
    (stroke (width 0) (type default))
  )
  (wire (pts (xy 166.37 110.49) (xy 175.26 110.49))
    (stroke (width 0) (type default))
  )
  (wire (pts (xy 26.67 214.63) (xy 26.67 232.41))
    (stroke (width 0) (type default))
  )
  (wire (pts (xy 394.97 55.88) (xy 400.05 55.88))
    (stroke (width 0) (type default))
  )
  (wire (pts (xy 48.26 59.69) (xy 39.37 59.69))
    (stroke (width 0) (type default))
  )
  (wire (pts (xy 41.91 207.01) (xy 41.91 209.55))
    (stroke (width 0) (type default))
  )
  (polyline (pts (xy 436.88 210.82) (xy 539.75 210.82))
    (stroke (width 0) (type dash))
  )

  (wire (pts (xy 273.05 91.44) (xy 273.05 93.98))
    (stroke (width 0) (type default))
  )
  (bus (pts (xy 190.5 74.93) (xy 190.5 69.85))
    (stroke (width 0) (type default))
  )

  (wire (pts (xy 86.36 259.08) (xy 93.98 259.08))
    (stroke (width 0) (type default))
  )
  (wire (pts (xy 26.67 29.21) (xy 26.67 30.48))
    (stroke (width 0) (type default))
  )
  (wire (pts (xy 233.68 62.23) (xy 238.76 62.23))
    (stroke (width 0) (type default))
  )
  (wire (pts (xy 93.98 29.21) (xy 104.14 29.21))
    (stroke (width 0) (type default))
  )
  (wire (pts (xy 27.94 262.89) (xy 27.94 261.62))
    (stroke (width 0) (type default))
  )
  (wire (pts (xy 295.91 121.92) (xy 303.53 121.92))
    (stroke (width 0) (type default))
  )
  (wire (pts (xy 48.26 62.23) (xy 39.37 62.23))
    (stroke (width 0) (type default))
  )
  (wire (pts (xy 233.68 146.05) (xy 238.76 146.05))
    (stroke (width 0) (type default))
  )
  (polyline (pts (xy 157.48 241.3) (xy 156.21 241.3))
    (stroke (width 0) (type dash))
  )

  (wire (pts (xy 391.16 27.94) (xy 400.05 27.94))
    (stroke (width 0) (type default))
  )
  (wire (pts (xy 48.26 276.86) (xy 52.07 276.86))
    (stroke (width 0) (type default))
  )
  (wire (pts (xy 135.89 254) (xy 151.13 254))
    (stroke (width 0) (type default))
  )
  (wire (pts (xy 353.06 132.08) (xy 367.03 132.08))
    (stroke (width 0) (type default))
  )
  (wire (pts (xy 294.64 86.36) (xy 303.53 86.36))
    (stroke (width 0) (type default))
  )
  (polyline (pts (xy 156.21 236.22) (xy 157.48 236.22))
    (stroke (width 0) (type dash))
  )

  (wire (pts (xy 294.64 78.74) (xy 303.53 78.74))
    (stroke (width 0) (type default))
  )
  (wire (pts (xy 238.76 153.67) (xy 224.79 153.67))
    (stroke (width 0) (type default))
  )
  (bus (pts (xy 187.96 156.21) (xy 191.77 156.21))
    (stroke (width 0) (type default))
  )

  (wire (pts (xy 135.89 29.21) (xy 135.89 30.48))
    (stroke (width 0) (type default))
  )
  (wire (pts (xy 238.76 196.85) (xy 224.79 196.85))
    (stroke (width 0) (type default))
  )
  (wire (pts (xy 361.95 99.06) (xy 367.03 99.06))
    (stroke (width 0) (type default))
  )
  (polyline (pts (xy 539.75 137.16) (xy 539.75 229.87))
    (stroke (width 0) (type dash))
  )

  (wire (pts (xy 294.64 137.16) (xy 303.53 137.16))
    (stroke (width 0) (type default))
  )
  (bus (pts (xy 254 74.93) (xy 254 69.85))
    (stroke (width 0) (type default))
  )

  (wire (pts (xy 86.36 228.6) (xy 93.98 228.6))
    (stroke (width 0) (type default))
  )
  (polyline (pts (xy 436.88 194.31) (xy 539.75 194.31))
    (stroke (width 0) (type dash))
  )
  (polyline (pts (xy 165.1 233.68) (xy 163.83 233.68))
    (stroke (width 0) (type dash))
  )

  (wire (pts (xy 26.67 36.83) (xy 38.1 36.83))
    (stroke (width 0) (type default))
  )
  (wire (pts (xy 361.95 81.28) (xy 367.03 81.28))
    (stroke (width 0) (type default))
  )
  (wire (pts (xy 233.68 138.43) (xy 238.76 138.43))
    (stroke (width 0) (type default))
  )
  (wire (pts (xy 111.76 158.75) (xy 102.87 158.75))
    (stroke (width 0) (type default))
  )
  (wire (pts (xy 48.26 35.56) (xy 48.26 36.83))
    (stroke (width 0) (type default))
  )
  (wire (pts (xy 114.3 36.83) (xy 125.73 36.83))
    (stroke (width 0) (type default))
  )
  (polyline (pts (xy 436.88 135.89) (xy 539.75 135.89))
    (stroke (width 0) (type dash))
  )

  (wire (pts (xy 227.33 29.21) (xy 238.76 29.21))
    (stroke (width 0) (type default))
  )
  (bus (pts (xy 254 110.49) (xy 251.46 110.49))
    (stroke (width 0) (type default))
  )

  (polyline (pts (xy 156.21 241.3) (xy 156.21 246.38))
    (stroke (width 0) (type dash))
  )

  (wire (pts (xy 93.98 35.56) (xy 93.98 36.83))
    (stroke (width 0) (type default))
  )
  (wire (pts (xy 93.98 241.3) (xy 86.36 241.3))
    (stroke (width 0) (type default))
  )
  (wire (pts (xy 41.91 207.01) (xy 52.07 207.01))
    (stroke (width 0) (type default))
  )
  (wire (pts (xy 86.36 236.22) (xy 93.98 236.22))
    (stroke (width 0) (type default))
  )
  (wire (pts (xy 294.64 144.78) (xy 303.53 144.78))
    (stroke (width 0) (type default))
  )
  (wire (pts (xy 228.6 262.89) (xy 236.22 262.89))
    (stroke (width 0) (type default))
  )
  (polyline (pts (xy 436.88 165.1) (xy 539.75 165.1))
    (stroke (width 0) (type dash))
  )

  (wire (pts (xy 38.1 29.21) (xy 48.26 29.21))
    (stroke (width 0) (type default))
  )
  (bus (pts (xy 254 69.85) (xy 251.46 69.85))
    (stroke (width 0) (type default))
  )

  (wire (pts (xy 238.76 133.35) (xy 233.68 133.35))
    (stroke (width 0) (type default))
  )
  (wire (pts (xy 86.36 243.84) (xy 93.98 243.84))
    (stroke (width 0) (type default))
  )
  (wire (pts (xy 157.48 190.5) (xy 171.45 190.5))
    (stroke (width 0) (type default))
  )
  (wire (pts (xy 381 27.94) (xy 391.16 27.94))
    (stroke (width 0) (type default))
  )
  (wire (pts (xy 97.79 186.69) (xy 109.22 186.69))
    (stroke (width 0) (type default))
  )
  (wire (pts (xy 201.93 234.95) (xy 209.55 234.95))
    (stroke (width 0) (type default))
  )
  (wire (pts (xy 48.26 36.83) (xy 59.69 36.83))
    (stroke (width 0) (type default))
  )
  (wire (pts (xy 238.76 36.83) (xy 250.19 36.83))
    (stroke (width 0) (type default))
  )
  (wire (pts (xy 48.26 77.47) (xy 39.37 77.47))
    (stroke (width 0) (type default))
  )
  (wire (pts (xy 111.76 57.15) (xy 102.87 57.15))
    (stroke (width 0) (type default))
  )
  (wire (pts (xy 381 34.29) (xy 381 35.56))
    (stroke (width 0) (type default))
  )
  (polyline (pts (xy 157.48 220.98) (xy 156.21 220.98))
    (stroke (width 0) (type dash))
  )

  (wire (pts (xy 111.76 85.09) (xy 102.87 85.09))
    (stroke (width 0) (type default))
  )
  (wire (pts (xy 41.91 214.63) (xy 41.91 217.17))
    (stroke (width 0) (type default))
  )
  (wire (pts (xy 86.36 218.44) (xy 93.98 218.44))
    (stroke (width 0) (type default))
  )
  (wire (pts (xy 102.87 125.73) (xy 111.76 125.73))
    (stroke (width 0) (type default))
  )
  (wire (pts (xy 294.64 195.58) (xy 303.53 195.58))
    (stroke (width 0) (type default))
  )
  (wire (pts (xy 97.79 198.12) (xy 97.79 194.31))
    (stroke (width 0) (type default))
  )
  (wire (pts (xy 86.36 248.92) (xy 93.98 248.92))
    (stroke (width 0) (type default))
  )
  (polyline (pts (xy 436.88 217.17) (xy 539.75 217.17))
    (stroke (width 0) (type dash))
  )

  (wire (pts (xy 227.33 36.83) (xy 227.33 40.64))
    (stroke (width 0) (type default))
  )
  (wire (pts (xy 76.2 57.15) (xy 78.74 57.15))
    (stroke (width 0) (type default))
  )
  (wire (pts (xy 104.14 151.13) (xy 111.76 151.13))
    (stroke (width 0) (type default))
  )
  (wire (pts (xy 187.96 29.21) (xy 198.12 29.21))
    (stroke (width 0) (type default))
  )
  (polyline (pts (xy 436.88 205.74) (xy 539.75 205.74))
    (stroke (width 0) (type dash))
  )

  (wire (pts (xy 154.94 190.5) (xy 157.48 190.5))
    (stroke (width 0) (type default))
  )
  (wire (pts (xy 135.89 259.08) (xy 151.13 259.08))
    (stroke (width 0) (type default))
  )
  (polyline (pts (xy 156.21 220.98) (xy 156.21 226.06))
    (stroke (width 0) (type dash))
  )

  (wire (pts (xy 233.68 161.29) (xy 238.76 161.29))
    (stroke (width 0) (type default))
  )
  (wire (pts (xy 48.26 29.21) (xy 59.69 29.21))
    (stroke (width 0) (type default))
  )
  (polyline (pts (xy 436.88 176.53) (xy 539.75 176.53))
    (stroke (width 0) (type dash))
  )

  (wire (pts (xy 238.76 201.93) (xy 224.79 201.93))
    (stroke (width 0) (type default))
  )
  (wire (pts (xy 233.68 143.51) (xy 238.76 143.51))
    (stroke (width 0) (type default))
  )
  (wire (pts (xy 294.64 60.96) (xy 303.53 60.96))
    (stroke (width 0) (type default))
  )
  (wire (pts (xy 104.14 36.83) (xy 114.3 36.83))
    (stroke (width 0) (type default))
  )
  (wire (pts (xy 381 35.56) (xy 391.16 35.56))
    (stroke (width 0) (type default))
  )
  (bus (pts (xy 190.5 69.85) (xy 187.96 69.85))
    (stroke (width 0) (type default))
  )

  (wire (pts (xy 238.76 156.21) (xy 233.68 156.21))
    (stroke (width 0) (type default))
  )
  (wire (pts (xy 233.68 176.53) (xy 238.76 176.53))
    (stroke (width 0) (type default))
  )
  (wire (pts (xy 353.06 35.56) (xy 353.06 39.37))
    (stroke (width 0) (type default))
  )
  (wire (pts (xy 294.64 66.04) (xy 303.53 66.04))
    (stroke (width 0) (type default))
  )
  (wire (pts (xy 52.07 264.16) (xy 52.07 265.43))
    (stroke (width 0) (type default))
  )
  (wire (pts (xy 166.37 113.03) (xy 175.26 113.03))
    (stroke (width 0) (type default))
  )
  (wire (pts (xy 135.89 29.21) (xy 144.78 29.21))
    (stroke (width 0) (type default))
  )
  (wire (pts (xy 86.36 238.76) (xy 93.98 238.76))
    (stroke (width 0) (type default))
  )
  (wire (pts (xy 270.51 29.21) (xy 270.51 57.15))
    (stroke (width 0) (type default))
  )
  (wire (pts (xy 361.95 101.6) (xy 367.03 101.6))
    (stroke (width 0) (type default))
  )
  (wire (pts (xy 25.4 262.89) (xy 27.94 262.89))
    (stroke (width 0) (type default))
  )
  (wire (pts (xy 294.64 149.86) (xy 303.53 149.86))
    (stroke (width 0) (type default))
  )
  (wire (pts (xy 52.07 275.59) (xy 52.07 276.86))
    (stroke (width 0) (type default))
  )
  (wire (pts (xy 363.22 27.94) (xy 363.22 29.21))
    (stroke (width 0) (type default))
  )
  (wire (pts (xy 182.88 190.5) (xy 182.88 218.44))
    (stroke (width 0) (type default))
  )
  (wire (pts (xy 233.68 67.31) (xy 238.76 67.31))
    (stroke (width 0) (type default))
  )
  (wire (pts (xy 102.87 107.95) (xy 111.76 107.95))
    (stroke (width 0) (type default))
  )
  (polyline (pts (xy 165.1 238.76) (xy 165.1 243.84))
    (stroke (width 0) (type dash))
  )

  (wire (pts (xy 353.06 144.78) (xy 367.03 144.78))
    (stroke (width 0) (type default))
  )
  (wire (pts (xy 294.64 147.32) (xy 303.53 147.32))
    (stroke (width 0) (type default))
  )
  (wire (pts (xy 167.64 29.21) (xy 177.8 29.21))
    (stroke (width 0) (type default))
  )
  (wire (pts (xy 38.1 29.21) (xy 38.1 30.48))
    (stroke (width 0) (type default))
  )
  (wire (pts (xy 233.68 57.15) (xy 238.76 57.15))
    (stroke (width 0) (type default))
  )
  (bus (pts (xy 251.46 151.13) (xy 254 151.13))
    (stroke (width 0) (type default))
  )

  (wire (pts (xy 294.64 203.2) (xy 303.53 203.2))
    (stroke (width 0) (type default))
  )
  (wire (pts (xy 167.64 29.21) (xy 167.64 30.48))
    (stroke (width 0) (type default))
  )
  (wire (pts (xy 233.68 166.37) (xy 238.76 166.37))
    (stroke (width 0) (type default))
  )
  (wire (pts (xy 238.76 191.77) (xy 224.79 191.77))
    (stroke (width 0) (type default))
  )
  (wire (pts (xy 294.64 213.36) (xy 303.53 213.36))
    (stroke (width 0) (type default))
  )
  (wire (pts (xy 294.64 175.26) (xy 303.53 175.26))
    (stroke (width 0) (type default))
  )
  (wire (pts (xy 157.48 35.56) (xy 157.48 36.83))
    (stroke (width 0) (type default))
  )
  (wire (pts (xy 177.8 36.83) (xy 187.96 36.83))
    (stroke (width 0) (type default))
  )
  (wire (pts (xy 111.76 80.01) (xy 102.87 80.01))
    (stroke (width 0) (type default))
  )
  (wire (pts (xy 135.89 220.98) (xy 142.24 220.98))
    (stroke (width 0) (type default))
  )
  (wire (pts (xy 344.17 231.14) (xy 346.71 231.14))
    (stroke (width 0) (type default))
  )
  (wire (pts (xy 48.26 264.16) (xy 52.07 264.16))
    (stroke (width 0) (type default))
  )
  (wire (pts (xy 372.11 27.94) (xy 381 27.94))
    (stroke (width 0) (type default))
  )
  (wire (pts (xy 370.84 232.41) (xy 370.84 234.95))
    (stroke (width 0) (type default))
  )
  (wire (pts (xy 111.76 77.47) (xy 102.87 77.47))
    (stroke (width 0) (type default))
  )
  (wire (pts (xy 135.89 36.83) (xy 135.89 35.56))
    (stroke (width 0) (type default))
  )
  (wire (pts (xy 157.48 36.83) (xy 157.48 40.64))
    (stroke (width 0) (type default))
  )
  (wire (pts (xy 213.36 255.27) (xy 236.22 255.27))
    (stroke (width 0) (type default))
  )
  (wire (pts (xy 151.13 220.98) (xy 147.32 220.98))
    (stroke (width 0) (type default))
  )
  (wire (pts (xy 111.76 105.41) (xy 102.87 105.41))
    (stroke (width 0) (type default))
  )
  (wire (pts (xy 114.3 29.21) (xy 114.3 30.48))
    (stroke (width 0) (type default))
  )
  (wire (pts (xy 233.68 85.09) (xy 238.76 85.09))
    (stroke (width 0) (type default))
  )
  (wire (pts (xy 278.13 91.44) (xy 303.53 91.44))
    (stroke (width 0) (type default))
  )
  (wire (pts (xy 233.68 64.77) (xy 238.76 64.77))
    (stroke (width 0) (type default))
  )
  (wire (pts (xy 48.26 264.16) (xy 48.26 267.97))
    (stroke (width 0) (type default))
  )
  (wire (pts (xy 294.64 68.58) (xy 303.53 68.58))
    (stroke (width 0) (type default))
  )
  (wire (pts (xy 171.45 190.5) (xy 182.88 190.5))
    (stroke (width 0) (type default))
  )
  (wire (pts (xy 135.89 236.22) (xy 151.13 236.22))
    (stroke (width 0) (type default))
  )
  (wire (pts (xy 102.87 118.11) (xy 111.76 118.11))
    (stroke (width 0) (type default))
  )
  (wire (pts (xy 166.37 125.73) (xy 175.26 125.73))
    (stroke (width 0) (type default))
  )
  (wire (pts (xy 86.36 220.98) (xy 93.98 220.98))
    (stroke (width 0) (type default))
  )
  (wire (pts (xy 151.13 256.54) (xy 135.89 256.54))
    (stroke (width 0) (type default))
  )
  (polyline (pts (xy 436.88 187.96) (xy 539.75 187.96))
    (stroke (width 0) (type dash))
  )

  (wire (pts (xy 48.26 163.83) (xy 39.37 163.83))
    (stroke (width 0) (type default))
  )
  (wire (pts (xy 270.51 57.15) (xy 266.7 57.15))
    (stroke (width 0) (type default))
  )
  (wire (pts (xy 331.47 36.83) (xy 331.47 35.56))
    (stroke (width 0) (type default))
  )
  (wire (pts (xy 157.48 200.66) (xy 157.48 198.12))
    (stroke (width 0) (type default))
  )
  (wire (pts (xy 260.35 35.56) (xy 260.35 36.83))
    (stroke (width 0) (type default))
  )
  (wire (pts (xy 238.76 186.69) (xy 224.79 186.69))
    (stroke (width 0) (type default))
  )
  (wire (pts (xy 294.64 73.66) (xy 303.53 73.66))
    (stroke (width 0) (type default))
  )
  (wire (pts (xy 278.13 91.44) (xy 278.13 93.98))
    (stroke (width 0) (type default))
  )
  (wire (pts (xy 86.36 261.62) (xy 93.98 261.62))
    (stroke (width 0) (type default))
  )
  (wire (pts (xy 187.96 36.83) (xy 198.12 36.83))
    (stroke (width 0) (type default))
  )
  (wire (pts (xy 125.73 35.56) (xy 125.73 36.83))
    (stroke (width 0) (type default))
  )
  (wire (pts (xy 135.89 218.44) (xy 142.24 218.44))
    (stroke (width 0) (type default))
  )
  (wire (pts (xy 109.22 194.31) (xy 109.22 193.04))
    (stroke (width 0) (type default))
  )
  (polyline (pts (xy 163.83 218.44) (xy 163.83 223.52))
    (stroke (width 0) (type dash))
  )

  (wire (pts (xy 228.6 260.35) (xy 236.22 260.35))
    (stroke (width 0) (type default))
  )
  (polyline (pts (xy 436.88 147.32) (xy 539.75 147.32))
    (stroke (width 0) (type dash))
  )

  (wire (pts (xy 201.93 240.03) (xy 209.55 240.03))
    (stroke (width 0) (type default))
  )
  (wire (pts (xy 294.64 205.74) (xy 303.53 205.74))
    (stroke (width 0) (type default))
  )
  (wire (pts (xy 233.68 151.13) (xy 238.76 151.13))
    (stroke (width 0) (type default))
  )
  (polyline (pts (xy 436.88 199.39) (xy 539.75 199.39))
    (stroke (width 0) (type dash))
  )

  (bus (pts (xy 187.96 74.93) (xy 190.5 74.93))
    (stroke (width 0) (type default))
  )

  (wire (pts (xy 238.76 125.73) (xy 233.68 125.73))
    (stroke (width 0) (type default))
  )
  (wire (pts (xy 294.64 160.02) (xy 303.53 160.02))
    (stroke (width 0) (type default))
  )
  (wire (pts (xy 111.76 102.87) (xy 102.87 102.87))
    (stroke (width 0) (type default))
  )
  (wire (pts (xy 109.22 186.69) (xy 125.73 186.69))
    (stroke (width 0) (type default))
  )
  (wire (pts (xy 353.06 152.4) (xy 367.03 152.4))
    (stroke (width 0) (type default))
  )
  (wire (pts (xy 26.67 35.56) (xy 26.67 36.83))
    (stroke (width 0) (type default))
  )
  (wire (pts (xy 353.06 139.7) (xy 367.03 139.7))
    (stroke (width 0) (type default))
  )
  (wire (pts (xy 294.64 76.2) (xy 303.53 76.2))
    (stroke (width 0) (type default))
  )
  (wire (pts (xy 69.85 29.21) (xy 69.85 30.48))
    (stroke (width 0) (type default))
  )
  (wire (pts (xy 97.79 194.31) (xy 109.22 194.31))
    (stroke (width 0) (type default))
  )
  (wire (pts (xy 102.87 110.49) (xy 111.76 110.49))
    (stroke (width 0) (type default))
  )
  (wire (pts (xy 41.91 222.25) (xy 41.91 223.52))
    (stroke (width 0) (type default))
  )
  (wire (pts (xy 48.26 166.37) (xy 39.37 166.37))
    (stroke (width 0) (type default))
  )
  (bus (pts (xy 251.46 74.93) (xy 254 74.93))
    (stroke (width 0) (type default))
  )

  (wire (pts (xy 48.26 67.31) (xy 39.37 67.31))
    (stroke (width 0) (type default))
  )
  (wire (pts (xy 294.64 165.1) (xy 303.53 165.1))
    (stroke (width 0) (type default))
  )
  (wire (pts (xy 22.86 232.41) (xy 26.67 232.41))
    (stroke (width 0) (type default))
  )
  (wire (pts (xy 294.64 81.28) (xy 303.53 81.28))
    (stroke (width 0) (type default))
  )
  (wire (pts (xy 93.98 226.06) (xy 86.36 226.06))
    (stroke (width 0) (type default))
  )
  (bus (pts (xy 254 191.77) (xy 251.46 191.77))
    (stroke (width 0) (type default))
  )

  (wire (pts (xy 233.68 72.39) (xy 238.76 72.39))
    (stroke (width 0) (type default))
  )
  (wire (pts (xy 157.48 196.85) (xy 157.48 198.12))
    (stroke (width 0) (type default))
  )
  (polyline (pts (xy 163.83 223.52) (xy 162.56 223.52))
    (stroke (width 0) (type dash))
  )

  (wire (pts (xy 97.79 186.69) (xy 97.79 187.96))
    (stroke (width 0) (type default))
  )
  (wire (pts (xy 26.67 207.01) (xy 26.67 209.55))
    (stroke (width 0) (type default))
  )
  (bus (pts (xy 243.84 137.16) (xy 261.62 137.16))
    (stroke (width 0) (type default))
  )

  (wire (pts (xy 208.28 57.15) (xy 203.2 57.15))
    (stroke (width 0) (type default))
  )
  (wire (pts (xy 111.76 69.85) (xy 102.87 69.85))
    (stroke (width 0) (type default))
  )
  (wire (pts (xy 48.26 29.21) (xy 48.26 30.48))
    (stroke (width 0) (type default))
  )
  (wire (pts (xy 294.64 83.82) (xy 303.53 83.82))
    (stroke (width 0) (type default))
  )
  (wire (pts (xy 104.14 153.67) (xy 111.76 153.67))
    (stroke (width 0) (type default))
  )
  (wire (pts (xy 166.37 115.57) (xy 175.26 115.57))
    (stroke (width 0) (type default))
  )
  (bus (pts (xy 187.96 115.57) (xy 190.5 115.57))
    (stroke (width 0) (type default))
  )

  (wire (pts (xy 48.26 87.63) (xy 39.37 87.63))
    (stroke (width 0) (type default))
  )
  (wire (pts (xy 294.64 63.5) (xy 303.53 63.5))
    (stroke (width 0) (type default))
  )
  (wire (pts (xy 27.94 255.27) (xy 27.94 256.54))
    (stroke (width 0) (type default))
  )
  (wire (pts (xy 86.36 251.46) (xy 93.98 251.46))
    (stroke (width 0) (type default))
  )
  (wire (pts (xy 198.12 29.21) (xy 208.28 29.21))
    (stroke (width 0) (type default))
  )
  (wire (pts (xy 391.16 27.94) (xy 391.16 29.21))
    (stroke (width 0) (type default))
  )
  (wire (pts (xy 111.76 87.63) (xy 102.87 87.63))
    (stroke (width 0) (type default))
  )
  (wire (pts (xy 104.14 148.59) (xy 111.76 148.59))
    (stroke (width 0) (type default))
  )
  (wire (pts (xy 294.64 58.42) (xy 303.53 58.42))
    (stroke (width 0) (type default))
  )
  (wire (pts (xy 228.6 275.59) (xy 236.22 275.59))
    (stroke (width 0) (type default))
  )
  (wire (pts (xy 224.79 181.61) (xy 238.76 181.61))
    (stroke (width 0) (type default))
  )
  (wire (pts (xy 166.37 105.41) (xy 175.26 105.41))
    (stroke (width 0) (type default))
  )
  (wire (pts (xy 238.76 90.17) (xy 224.79 90.17))
    (stroke (width 0) (type default))
  )
  (wire (pts (xy 48.26 256.54) (xy 48.26 252.73))
    (stroke (width 0) (type default))
  )
  (wire (pts (xy 48.26 261.62) (xy 48.26 264.16))
    (stroke (width 0) (type default))
  )
  (polyline (pts (xy 436.88 182.88) (xy 539.75 182.88))
    (stroke (width 0) (type dash))
  )

  (wire (pts (xy 361.95 88.9) (xy 367.03 88.9))
    (stroke (width 0) (type default))
  )
  (wire (pts (xy 294.64 142.24) (xy 303.53 142.24))
    (stroke (width 0) (type default))
  )
  (wire (pts (xy 400.05 27.94) (xy 400.05 55.88))
    (stroke (width 0) (type default))
  )
  (wire (pts (xy 250.19 36.83) (xy 260.35 36.83))
    (stroke (width 0) (type default))
  )
  (wire (pts (xy 309.88 36.83) (xy 321.31 36.83))
    (stroke (width 0) (type default))
  )
  (wire (pts (xy 353.06 170.18) (xy 367.03 170.18))
    (stroke (width 0) (type default))
  )
  (wire (pts (xy 59.69 29.21) (xy 59.69 30.48))
    (stroke (width 0) (type default))
  )
  (wire (pts (xy 340.36 55.88) (xy 340.36 29.21))
    (stroke (width 0) (type default))
  )
  (wire (pts (xy 147.32 218.44) (xy 151.13 218.44))
    (stroke (width 0) (type default))
  )
  (wire (pts (xy 309.88 35.56) (xy 309.88 36.83))
    (stroke (width 0) (type default))
  )
  (wire (pts (xy 227.33 35.56) (xy 227.33 36.83))
    (stroke (width 0) (type default))
  )
  (polyline (pts (xy 436.88 222.25) (xy 539.75 222.25))
    (stroke (width 0) (type dash))
  )

  (bus (pts (xy 191.77 156.21) (xy 191.77 151.13))
    (stroke (width 0) (type default))
  )

  (wire (pts (xy 78.74 57.15) (xy 78.74 29.21))
    (stroke (width 0) (type default))
  )
  (wire (pts (xy 201.93 237.49) (xy 209.55 237.49))
    (stroke (width 0) (type default))
  )
  (bus (pts (xy 180.34 137.16) (xy 198.12 137.16))
    (stroke (width 0) (type default))
  )

  (wire (pts (xy 294.64 162.56) (xy 303.53 162.56))
    (stroke (width 0) (type default))
  )
  (wire (pts (xy 171.45 190.5) (xy 171.45 191.77))
    (stroke (width 0) (type default))
  )
  (wire (pts (xy 102.87 128.27) (xy 111.76 128.27))
    (stroke (width 0) (type default))
  )
  (wire (pts (xy 363.22 35.56) (xy 372.11 35.56))
    (stroke (width 0) (type default))
  )
  (polyline (pts (xy 163.83 228.6) (xy 165.1 228.6))
    (stroke (width 0) (type dash))
  )

  (wire (pts (xy 151.13 246.38) (xy 135.89 246.38))
    (stroke (width 0) (type default))
  )
  (wire (pts (xy 48.26 64.77) (xy 39.37 64.77))
    (stroke (width 0) (type default))
  )
  (wire (pts (xy 201.93 232.41) (xy 209.55 232.41))
    (stroke (width 0) (type default))
  )
  (wire (pts (xy 104.14 35.56) (xy 104.14 36.83))
    (stroke (width 0) (type default))
  )
  (wire (pts (xy 361.95 93.98) (xy 367.03 93.98))
    (stroke (width 0) (type default))
  )
  (wire (pts (xy 26.67 29.21) (xy 38.1 29.21))
    (stroke (width 0) (type default))
  )
  (wire (pts (xy 93.98 29.21) (xy 93.98 30.48))
    (stroke (width 0) (type default))
  )
  (wire (pts (xy 125.73 213.36) (xy 121.92 213.36))
    (stroke (width 0) (type default))
  )
  (wire (pts (xy 372.11 27.94) (xy 372.11 29.21))
    (stroke (width 0) (type default))
  )
  (wire (pts (xy 166.37 118.11) (xy 175.26 118.11))
    (stroke (width 0) (type default))
  )
  (wire (pts (xy 177.8 35.56) (xy 177.8 36.83))
    (stroke (width 0) (type default))
  )
  (wire (pts (xy 41.91 236.22) (xy 41.91 237.49))
    (stroke (width 0) (type default))
  )
  (wire (pts (xy 294.64 157.48) (xy 303.53 157.48))
    (stroke (width 0) (type default))
  )
  (wire (pts (xy 27.94 247.65) (xy 27.94 250.19))
    (stroke (width 0) (type default))
  )
  (wire (pts (xy 233.68 140.97) (xy 238.76 140.97))
    (stroke (width 0) (type default))
  )
  (wire (pts (xy 111.76 64.77) (xy 102.87 64.77))
    (stroke (width 0) (type default))
  )
  (polyline (pts (xy 163.83 238.76) (xy 165.1 238.76))
    (stroke (width 0) (type dash))
  )

  (wire (pts (xy 157.48 36.83) (xy 167.64 36.83))
    (stroke (width 0) (type default))
  )
  (wire (pts (xy 157.48 29.21) (xy 157.48 30.48))
    (stroke (width 0) (type default))
  )
  (wire (pts (xy 27.94 247.65) (xy 29.21 247.65))
    (stroke (width 0) (type default))
  )
  (polyline (pts (xy 157.48 231.14) (xy 156.21 231.14))
    (stroke (width 0) (type dash))
  )

  (wire (pts (xy 97.79 193.04) (xy 97.79 194.31))
    (stroke (width 0) (type default))
  )
  (wire (pts (xy 135.89 228.6) (xy 151.13 228.6))
    (stroke (width 0) (type default))
  )
  (wire (pts (xy 52.07 276.86) (xy 52.07 278.13))
    (stroke (width 0) (type default))
  )
  (wire (pts (xy 294.64 167.64) (xy 303.53 167.64))
    (stroke (width 0) (type default))
  )
  (wire (pts (xy 233.68 171.45) (xy 238.76 171.45))
    (stroke (width 0) (type default))
  )
  (wire (pts (xy 294.64 210.82) (xy 303.53 210.82))
    (stroke (width 0) (type default))
  )
  (wire (pts (xy 125.73 29.21) (xy 125.73 30.48))
    (stroke (width 0) (type default))
  )
  (wire (pts (xy 125.73 36.83) (xy 135.89 36.83))
    (stroke (width 0) (type default))
  )
  (wire (pts (xy 294.64 116.84) (xy 303.53 116.84))
    (stroke (width 0) (type default))
  )
  (wire (pts (xy 367.03 157.48) (xy 353.06 157.48))
    (stroke (width 0) (type default))
  )
  (polyline (pts (xy 162.56 218.44) (xy 163.83 218.44))
    (stroke (width 0) (type dash))
  )

  (wire (pts (xy 294.64 177.8) (xy 303.53 177.8))
    (stroke (width 0) (type default))
  )
  (wire (pts (xy 353.06 147.32) (xy 367.03 147.32))
    (stroke (width 0) (type default))
  )
  (wire (pts (xy 233.68 69.85) (xy 238.76 69.85))
    (stroke (width 0) (type default))
  )
  (wire (pts (xy 294.64 208.28) (xy 303.53 208.28))
    (stroke (width 0) (type default))
  )
  (wire (pts (xy 299.72 29.21) (xy 299.72 30.48))
    (stroke (width 0) (type default))
  )
  (wire (pts (xy 139.7 57.15) (xy 144.78 57.15))
    (stroke (width 0) (type default))
  )
  (wire (pts (xy 48.26 90.17) (xy 39.37 90.17))
    (stroke (width 0) (type default))
  )
  (wire (pts (xy 233.68 95.25) (xy 238.76 95.25))
    (stroke (width 0) (type default))
  )
  (bus (pts (xy 243.84 177.8) (xy 261.62 177.8))
    (stroke (width 0) (type default))
  )

  (wire (pts (xy 353.06 27.94) (xy 363.22 27.94))
    (stroke (width 0) (type default))
  )
  (polyline (pts (xy 156.21 231.14) (xy 156.21 236.22))
    (stroke (width 0) (type dash))
  )

  (wire (pts (xy 294.64 172.72) (xy 303.53 172.72))
    (stroke (width 0) (type default))
  )
  (wire (pts (xy 238.76 207.01) (xy 224.79 207.01))
    (stroke (width 0) (type default))
  )
  (wire (pts (xy 238.76 80.01) (xy 233.68 80.01))
    (stroke (width 0) (type default))
  )
  (wire (pts (xy 238.76 189.23) (xy 224.79 189.23))
    (stroke (width 0) (type default))
  )
  (wire (pts (xy 224.79 29.21) (xy 227.33 29.21))
    (stroke (width 0) (type default))
  )
  (wire (pts (xy 309.88 29.21) (xy 309.88 30.48))
    (stroke (width 0) (type default))
  )
  (wire (pts (xy 209.55 257.81) (xy 236.22 257.81))
    (stroke (width 0) (type default))
  )
  (wire (pts (xy 294.64 152.4) (xy 303.53 152.4))
    (stroke (width 0) (type default))
  )
  (wire (pts (xy 233.68 59.69) (xy 238.76 59.69))
    (stroke (width 0) (type default))
  )
  (wire (pts (xy 198.12 35.56) (xy 198.12 36.83))
    (stroke (width 0) (type default))
  )
  (wire (pts (xy 166.37 120.65) (xy 175.26 120.65))
    (stroke (width 0) (type default))
  )
  (wire (pts (xy 104.14 156.21) (xy 111.76 156.21))
    (stroke (width 0) (type default))
  )
  (wire (pts (xy 86.36 246.38) (xy 93.98 246.38))
    (stroke (width 0) (type default))
  )
  (wire (pts (xy 147.32 223.52) (xy 151.13 223.52))
    (stroke (width 0) (type default))
  )
  (wire (pts (xy 187.96 35.56) (xy 187.96 36.83))
    (stroke (width 0) (type default))
  )
  (wire (pts (xy 52.07 264.16) (xy 55.88 264.16))
    (stroke (width 0) (type default))
  )
  (wire (pts (xy 273.05 91.44) (xy 278.13 91.44))
    (stroke (width 0) (type default))
  )
  (wire (pts (xy 224.79 130.81) (xy 238.76 130.81))
    (stroke (width 0) (type default))
  )
  (wire (pts (xy 69.85 29.21) (xy 78.74 29.21))
    (stroke (width 0) (type default))
  )
  (wire (pts (xy 363.22 34.29) (xy 363.22 35.56))
    (stroke (width 0) (type default))
  )
  (wire (pts (xy 353.06 34.29) (xy 353.06 35.56))
    (stroke (width 0) (type default))
  )
  (wire (pts (xy 250.19 29.21) (xy 250.19 30.48))
    (stroke (width 0) (type default))
  )
  (wire (pts (xy 340.36 29.21) (xy 331.47 29.21))
    (stroke (width 0) (type default))
  )
  (wire (pts (xy 238.76 217.17) (xy 233.68 217.17))
    (stroke (width 0) (type default))
  )
  (wire (pts (xy 201.93 257.81) (xy 204.47 257.81))
    (stroke (width 0) (type default))
  )
  (polyline (pts (xy 156.21 226.06) (xy 157.48 226.06))
    (stroke (width 0) (type dash))
  )

  (wire (pts (xy 299.72 36.83) (xy 309.88 36.83))
    (stroke (width 0) (type default))
  )
  (wire (pts (xy 331.47 55.88) (xy 340.36 55.88))
    (stroke (width 0) (type default))
  )
  (wire (pts (xy 111.76 67.31) (xy 102.87 67.31))
    (stroke (width 0) (type default))
  )
  (wire (pts (xy 91.44 29.21) (xy 93.98 29.21))
    (stroke (width 0) (type default))
  )
  (wire (pts (xy 157.48 198.12) (xy 171.45 198.12))
    (stroke (width 0) (type default))
  )
  (wire (pts (xy 273.05 88.9) (xy 273.05 91.44))
    (stroke (width 0) (type default))
  )
  (wire (pts (xy 167.64 35.56) (xy 167.64 36.83))
    (stroke (width 0) (type default))
  )
  (wire (pts (xy 288.29 29.21) (xy 288.29 30.48))
    (stroke (width 0) (type default))
  )
  (bus (pts (xy 180.34 96.52) (xy 198.12 96.52))
    (stroke (width 0) (type default))
  )
  (bus (pts (xy 191.77 151.13) (xy 187.96 151.13))
    (stroke (width 0) (type default))
  )

  (wire (pts (xy 299.72 29.21) (xy 309.88 29.21))
    (stroke (width 0) (type default))
  )
  (wire (pts (xy 372.11 234.95) (xy 370.84 234.95))
    (stroke (width 0) (type default))
  )
  (polyline (pts (xy 436.88 171.45) (xy 539.75 171.45))
    (stroke (width 0) (type dash))
  )

  (wire (pts (xy 111.76 100.33) (xy 102.87 100.33))
    (stroke (width 0) (type default))
  )
  (wire (pts (xy 86.36 231.14) (xy 93.98 231.14))
    (stroke (width 0) (type default))
  )
  (wire (pts (xy 104.14 29.21) (xy 104.14 30.48))
    (stroke (width 0) (type default))
  )
  (polyline (pts (xy 462.28 130.81) (xy 462.28 228.6))
    (stroke (width 0) (type dash))
  )

  (wire (pts (xy 238.76 35.56) (xy 238.76 36.83))
    (stroke (width 0) (type default))
  )
  (wire (pts (xy 69.85 36.83) (xy 69.85 35.56))
    (stroke (width 0) (type default))
  )
  (wire (pts (xy 86.36 215.9) (xy 93.98 215.9))
    (stroke (width 0) (type default))
  )
  (wire (pts (xy 260.35 29.21) (xy 270.51 29.21))
    (stroke (width 0) (type default))
  )
  (wire (pts (xy 25.4 247.65) (xy 25.4 250.19))
    (stroke (width 0) (type default))
  )
  (polyline (pts (xy 436.88 137.16) (xy 436.88 229.87))
    (stroke (width 0) (type dash))
  )

  (wire (pts (xy 102.87 120.65) (xy 111.76 120.65))
    (stroke (width 0) (type default))
  )
  (wire (pts (xy 227.33 29.21) (xy 227.33 30.48))
    (stroke (width 0) (type default))
  )
  (polyline (pts (xy 436.88 158.75) (xy 539.75 158.75))
    (stroke (width 0) (type dash))
  )

  (wire (pts (xy 125.73 186.69) (xy 125.73 213.36))
    (stroke (width 0) (type default))
  )
  (wire (pts (xy 171.45 177.8) (xy 171.45 168.91))
    (stroke (width 0) (type default))
  )
  (wire (pts (xy 151.13 248.92) (xy 135.89 248.92))
    (stroke (width 0) (type default))
  )
  (wire (pts (xy 154.94 29.21) (xy 157.48 29.21))
    (stroke (width 0) (type default))
  )
  (wire (pts (xy 187.96 29.21) (xy 187.96 30.48))
    (stroke (width 0) (type default))
  )
  (wire (pts (xy 111.76 72.39) (xy 102.87 72.39))
    (stroke (width 0) (type default))
  )
  (wire (pts (xy 238.76 29.21) (xy 238.76 30.48))
    (stroke (width 0) (type default))
  )
  (wire (pts (xy 171.45 168.91) (xy 175.26 168.91))
    (stroke (width 0) (type default))
  )
  (polyline (pts (xy 511.81 130.81) (xy 511.81 229.87))
    (stroke (width 0) (type dash))
  )

  (wire (pts (xy 59.69 35.56) (xy 59.69 36.83))
    (stroke (width 0) (type default))
  )
  (wire (pts (xy 381 27.94) (xy 381 29.21))
    (stroke (width 0) (type default))
  )
  (wire (pts (xy 228.6 278.13) (xy 236.22 278.13))
    (stroke (width 0) (type default))
  )
  (wire (pts (xy 48.26 161.29) (xy 39.37 161.29))
    (stroke (width 0) (type default))
  )
  (wire (pts (xy 135.89 251.46) (xy 151.13 251.46))
    (stroke (width 0) (type default))
  )
  (wire (pts (xy 238.76 29.21) (xy 250.19 29.21))
    (stroke (width 0) (type default))
  )
  (wire (pts (xy 59.69 29.21) (xy 69.85 29.21))
    (stroke (width 0) (type default))
  )
  (wire (pts (xy 114.3 35.56) (xy 114.3 36.83))
    (stroke (width 0) (type default))
  )
  (wire (pts (xy 111.76 90.17) (xy 102.87 90.17))
    (stroke (width 0) (type default))
  )
  (wire (pts (xy 95.25 186.69) (xy 97.79 186.69))
    (stroke (width 0) (type default))
  )
  (wire (pts (xy 171.45 198.12) (xy 171.45 196.85))
    (stroke (width 0) (type default))
  )
  (bus (pts (xy 190.5 115.57) (xy 190.5 110.49))
    (stroke (width 0) (type default))
  )

  (wire (pts (xy 321.31 36.83) (xy 331.47 36.83))
    (stroke (width 0) (type default))
  )
  (wire (pts (xy 353.06 27.94) (xy 353.06 29.21))
    (stroke (width 0) (type default))
  )
  (wire (pts (xy 288.29 36.83) (xy 288.29 39.37))
    (stroke (width 0) (type default))
  )
  (wire (pts (xy 288.29 36.83) (xy 299.72 36.83))
    (stroke (width 0) (type default))
  )
  (wire (pts (xy 294.64 93.98) (xy 303.53 93.98))
    (stroke (width 0) (type default))
  )
  (bus (pts (xy 190.5 110.49) (xy 187.96 110.49))
    (stroke (width 0) (type default))
  )

  (wire (pts (xy 238.76 115.57) (xy 224.79 115.57))
    (stroke (width 0) (type default))
  )
  (wire (pts (xy 167.64 36.83) (xy 177.8 36.83))
    (stroke (width 0) (type default))
  )
  (wire (pts (xy 144.78 57.15) (xy 144.78 29.21))
    (stroke (width 0) (type default))
  )
  (polyline (pts (xy 165.1 228.6) (xy 165.1 233.68))
    (stroke (width 0) (type dash))
  )

  (wire (pts (xy 102.87 115.57) (xy 111.76 115.57))
    (stroke (width 0) (type default))
  )
  (wire (pts (xy 48.26 158.75) (xy 39.37 158.75))
    (stroke (width 0) (type default))
  )
  (wire (pts (xy 367.03 232.41) (xy 370.84 232.41))
    (stroke (width 0) (type default))
  )
  (wire (pts (xy 227.33 36.83) (xy 238.76 36.83))
    (stroke (width 0) (type default))
  )
  (wire (pts (xy 93.98 36.83) (xy 104.14 36.83))
    (stroke (width 0) (type default))
  )
  (wire (pts (xy 294.64 180.34) (xy 303.53 180.34))
    (stroke (width 0) (type default))
  )
  (wire (pts (xy 109.22 186.69) (xy 109.22 187.96))
    (stroke (width 0) (type default))
  )
  (wire (pts (xy 86.36 271.78) (xy 93.98 271.78))
    (stroke (width 0) (type default))
  )
  (wire (pts (xy 224.79 194.31) (xy 238.76 194.31))
    (stroke (width 0) (type default))
  )
  (wire (pts (xy 353.06 167.64) (xy 367.03 167.64))
    (stroke (width 0) (type default))
  )
  (wire (pts (xy 294.64 190.5) (xy 303.53 190.5))
    (stroke (width 0) (type default))
  )

  (text "PCLKT0_0" (at 12.7 62.865 0)
    (effects (font (size 1.27 1.27)) (justify left bottom))
  )
  (text "?\n\n" (at 495.3 214.63 0)
    (effects (font (size 2.9972 2.9972)) (justify left bottom))
  )
  (text "PCLKT2_1" (at 162.56 65.405 0)
    (effects (font (size 1.27 1.27)) (justify left bottom))
  )
  (text "Y" (at 495.935 170.18 0)
    (effects (font (size 2.9972 2.9972)) (justify left bottom))
  )
  (text "N\n" (at 495.3 163.83 0)
    (effects (font (size 2.9972 2.9972)) (justify left bottom))
  )
  (text "DDR3" (at 302.26 19.685 0)
    (effects (font (size 2.9972 2.9972)) (justify left bottom))
  )
  (text "PCLKT6_1" (at 271.78 56.515 0)
    (effects (font (size 1.27 1.27)) (justify left bottom))
  )
  (text "JTAG" (at 205.74 226.06 0)
    (effects (font (size 2.9972 2.9972)) (justify left bottom))
  )
  (text "QSPI1" (at 438.15 158.115 0)
    (effects (font (size 2.9972 2.9972)) (justify left bottom))
  )
  (text "ECPIX5" (at 463.55 134.62 0)
    (effects (font (size 2.0066 2.0066)) (justify left bottom))
  )
  (text "PCLKT6_0" (at 271.78 59.055 0)
    (effects (font (size 1.27 1.27)) (justify left bottom))
  )
  (text "N\n" (at 495.3 193.04 0)
    (effects (font (size 2.9972 2.9972)) (justify left bottom))
  )
  (text "I3C" (at 445.77 146.685 0)
    (effects (font (size 2.9972 2.9972)) (justify right bottom))
  )
  (text "PCLKC0_1" (at 12.7 60.325 0)
    (effects (font (size 1.27 1.27)) (justify left bottom))
  )
  (text "PCLKT7_1" (at 332.74 168.91 0)
    (effects (font (size 1.27 1.27)) (justify left bottom))
  )
  (text "?\n\n" (at 495.3 186.055 0)
    (effects (font (size 2.9972 2.9972)) (justify left bottom))
  )
  (text "N\n" (at 495.3 140.335 0)
    (effects (font (size 2.9972 2.9972)) (justify left bottom))
  )
  (text "SGPIO" (at 437.515 193.04 0)
    (effects (font (size 2.9972 2.9972)) (justify left bottom))
  )
  (text "USB1 between HPM and BMC\nUSB2 between BMC and HPM expansion"
    (at 24.765 194.945 90)
    (effects (font (size 1.27 1.27)) (justify left bottom))
  )
  (text "UART" (at 437.515 198.755 0)
    (effects (font (size 2.9972 2.9972)) (justify left bottom))
  )
  (text "NCSI" (at 437.515 210.185 0)
    (effects (font (size 2.9972 2.9972)) (justify left bottom))
  )
  (text "PCLKT3_0" (at 207.01 215.9 0)
    (effects (font (size 1.27 1.27)) (justify left bottom))
  )
  (text "SPI0" (at 438.15 163.83 0)
    (effects (font (size 2.9972 2.9972)) (justify left bottom))
  )
  (text "DEDICATED_PINS?" (at 484.505 128.27 0)
    (effects (font (size 2.0066 2.0066)) (justify left bottom))
  )
  (text "Status" (at 518.795 128.905 0)
    (effects (font (size 2.9972 2.9972)) (justify left bottom))
  )
  (text "Y" (at 495.935 175.895 0)
    (effects (font (size 2.9972 2.9972)) (justify left bottom))
  )
  (text "JTAG" (at 437.515 175.26 0)
    (effects (font (size 2.9972 2.9972)) (justify left bottom))
  )
  (text "DONE/check" (at 511.175 169.545 0)
    (effects (font (size 2.9972 2.9972)) (justify left bottom))
  )
  (text "PCLKC1_0" (at 124.46 169.545 0)
    (effects (font (size 1.27 1.27)) (justify left bottom))
  )
  (text "DONE" (at 519.43 215.265 0)
    (effects (font (size 2.9972 2.9972)) (justify left bottom))
  )
  (text "DONE" (at 519.43 175.26 0)
    (effects (font (size 2.9972 2.9972)) (justify left bottom))
  )
  (text "Y" (at 495.935 152.4 0)
    (effects (font (size 2.9972 2.9972)) (justify left bottom))
  )
  (text "PCLKC2_0" (at 162.56 57.785 0)
    (effects (font (size 1.27 1.27)) (justify left bottom))
  )
  (text "OCP" (at 467.995 157.48 0)
    (effects (font (size 2.0066 2.0066)) (justify left bottom))
  )
  (text "PCLKT7_0" (at 332.74 171.45 0)
    (effects (font (size 1.27 1.27)) (justify left bottom))
  )
  (text "Y" (at 495.935 134.62 0)
    (effects (font (size 2.9972 2.9972)) (justify left bottom))
  )
  (text "PCLKT1_1" (at 124.46 177.165 0)
    (effects (font (size 1.27 1.27)) (justify left bottom))
  )
  (text "CLK->P28" (at 484.505 220.98 0)
    (effects (font (size 2.9972 2.9972)) (justify left bottom))
  )
  (text "PCLKT0_1" (at 12.7 65.405 0)
    (effects (font (size 1.27 1.27)) (justify left bottom))
  )
  (text "PCIe x1" (at 437.515 169.545 0)
    (effects (font (size 2.9972 2.9972)) (justify left bottom))
  )
  (text "ECPIX5" (at 466.09 214.63 0)
    (effects (font (size 2.0066 2.0066)) (justify left bottom))
  )
  (text "DONE" (at 519.43 220.98 0)
    (effects (font (size 2.9972 2.9972)) (justify left bottom))
  )
  (text "Reference" (at 461.01 128.905 0)
    (effects (font (size 2.9972 2.9972)) (justify left bottom))
  )
  (text "DDR3_CS and DDR3_RESET\nnot used in Ref" (at 273.685 113.665 0)
    (effects (font (size 1.27 1.27)) (justify left bottom))
  )
  (text "PCLKC7_0" (at 332.74 176.53 0)
    (effects (font (size 1.27 1.27)) (justify left bottom))
  )
  (text "DONE" (at 519.43 226.695 0)
    (effects (font (size 2.9972 2.9972)) (justify left bottom))
  )
  (text "ESPI" (at 437.515 187.325 0)
    (effects (font (size 2.9972 2.9972)) (justify left bottom))
  )
  (text "D7/IO7\n\nD5/MISO2/IO5\n\nD6/IO6\n\nD4/MOSI2/IO4\n\nD3/IO3\n\nD1/MISO/IO1\n\nD2/IO2\n\nD0/MOSI/IO0\n\nSN/CSN\n\nHOLDN/DI/BUSY/CSSPIN/CEN\n\nCS1N\n\nDOUT/CSON\n\nWRITEN\n\nINITN\n\nCCLK,8,MCLK/SCK"
    (at 166.116 254.381 0)
    (effects (font (size 0.762 0.762)) (justify left bottom))
  )
  (text "-" (at 469.9 151.13 0)
    (effects (font (size 2.0066 2.0066)) (justify left bottom))
  )
  (text "CLK->N26" (at 484.505 226.695 0)
    (effects (font (size 2.9972 2.9972)) (justify left bottom))
  )
  (text "PCLKC0_0" (at 12.7 57.785 0)
    (effects (font (size 1.27 1.27)) (justify left bottom))
  )
  (text "Y" (at 495.3 215.9 0)
    (effects (font (size 2.9972 2.9972)) (justify left bottom))
  )
  (text "DONE" (at 519.43 151.765 0)
    (effects (font (size 2.9972 2.9972)) (justify left bottom))
  )
  (text "ECP5" (at 467.995 175.26 0)
    (effects (font (size 2.0066 2.0066)) (justify left bottom))
  )
  (text "PCLKT1_0" (at 124.46 174.625 0)
    (effects (font (size 1.27 1.27)) (justify left bottom))
  )
  (text "eMMC" (at 437.515 180.975 0)
    (effects (font (size 2.9972 2.9972)) (justify left bottom))
  )
  (text "RGMII" (at 437.515 215.265 0)
    (effects (font (size 2.9972 2.9972)) (justify left bottom))
  )
  (text "ECP5_VERSA\n" (at 462.915 169.545 0)
    (effects (font (size 2.0066 2.0066)) (justify left bottom))
  )
  (text "DDR3" (at 438.15 135.255 0)
    (effects (font (size 2.9972 2.9972)) (justify left bottom))
  )
  (text "1V8" (at 159.385 104.14 0)
    (effects (font (size 1.27 1.27)) (justify left bottom))
  )
  (text "ULPI2" (at 438.15 226.695 0)
    (effects (font (size 2.9972 2.9972)) (justify left bottom))
  )
  (text "PCIe x1" (at 233.68 249.555 0)
    (effects (font (size 2.9972 2.9972)) (justify left bottom))
  )
  (text "N\n" (at 495.3 198.755 0)
    (effects (font (size 2.9972 2.9972)) (justify left bottom))
  )
  (text "PCLKC1_1" (at 124.46 172.085 0)
    (effects (font (size 1.27 1.27)) (justify left bottom))
  )
  (text "-" (at 469.9 146.05 0)
    (effects (font (size 2.0066 2.0066)) (justify left bottom))
  )
  (text "ethernet.sch" (at 20.32 81.915 90)
    (effects (font (size 1.27 1.27)) (justify left bottom))
  )
  (text "Misc orphans: move freely" (at 208.28 184.785 0)
    (effects (font (size 1.27 1.27)) (justify left bottom))
  )
  (text "N\n" (at 495.3 146.05 0)
    (effects (font (size 2.9972 2.9972)) (justify left bottom))
  )
  (text "TBD: should additional GPIO\npin be considered as\nBootStrap pin\n(OCP mentions 50k pulldown)"
    (at 128.905 282.575 0)
    (effects (font (size 1.27 1.27)) (justify left bottom))
  )
  (text "FPGA connections to be established while preparing layout"
    (at 17.145 19.05 0)
    (effects (font (size 1.27 1.27)) (justify left bottom))
  )
  (text "ROT_SPI" (at 438.15 152.4 0)
    (effects (font (size 2.9972 2.9972)) (justify left bottom))
  )
  (text "Vref" (at 251.46 182.245 0)
    (effects (font (size 1.27 1.27)) (justify left bottom))
  )
  (text "I2C" (at 445.77 140.97 0)
    (effects (font (size 2.9972 2.9972)) (justify right bottom))
  )
  (text "PCLKC2_1" (at 162.56 60.325 0)
    (effects (font (size 1.27 1.27)) (justify left bottom))
  )
  (text "ULPI1" (at 438.15 221.615 0)
    (effects (font (size 2.9972 2.9972)) (justify left bottom))
  )
  (text "PCLKC3_1" (at 207.01 213.36 0)
    (effects (font (size 1.27 1.27)) (justify left bottom))
  )
  (text "PCLKT3_1" (at 207.01 218.44 0)
    (effects (font (size 1.27 1.27)) (justify left bottom))
  )
  (text "PCLKC3_0" (at 207.01 210.82 0)
    (effects (font (size 1.27 1.27)) (justify left bottom))
  )
  (text "RGMII_REFCLK is movable:\nnot used in Ref" (at 16.51 51.435 0)
    (effects (font (size 1.27 1.27)) (justify left bottom))
  )
  (text "2xUSB 2.0" (at 437.515 203.835 0)
    (effects (font (size 2.9972 2.9972)) (justify left bottom))
  )
  (text "N\n" (at 495.3 157.48 0)
    (effects (font (size 2.9972 2.9972)) (justify left bottom))
  )
  (text "DONE" (at 519.43 134.62 0)
    (effects (font (size 2.9972 2.9972)) (justify left bottom))
  )
  (text "Interface" (at 438.15 128.905 0)
    (effects (font (size 2.9972 2.9972)) (justify left bottom))
  )
  (text "PCLKC6_1" (at 271.78 61.595 0)
    (effects (font (size 1.27 1.27)) (justify left bottom))
  )
  (text "N\n" (at 495.3 204.47 0)
    (effects (font (size 2.9972 2.9972)) (justify left bottom))
  )
  (text "N\n" (at 495.3 187.325 0)
    (effects (font (size 2.9972 2.9972)) (justify left bottom))
  )
  (text "ROT_SPI" (at 139.7 188.595 0)
    (effects (font (size 2.9972 2.9972)) (justify left bottom))
  )
  (text "PCLKC6_0" (at 271.78 64.135 0)
    (effects (font (size 1.27 1.27)) (justify left bottom))
  )
  (text "PCLKC7_1" (at 332.74 173.99 0)
    (effects (font (size 1.27 1.27)) (justify left bottom))
  )
  (text "PCLKT2_0" (at 162.56 62.865 0)
    (effects (font (size 1.27 1.27)) (justify left bottom))
  )
  (text "Trellis board" (at 462.28 203.2 0)
    (effects (font (size 2.0066 2.0066)) (justify left bottom))
  )

  (label "PCIE_BMC_TX_C_DN" (at 217.17 257.81 0) (fields_autoplaced)
    (effects (font (size 1.27 1.27)) (justify left bottom))
  )
  (label "PCIE_BMC_TX_C_DP" (at 217.17 255.27 0) (fields_autoplaced)
    (effects (font (size 1.27 1.27)) (justify left bottom))
  )

  (global_label "I2C[5]_SCL" (shape input) (at 102.87 59.69 180) (fields_autoplaced)
    (effects (font (size 1.27 1.27)) (justify right))
    (property "Intersheetrefs" "${INTERSHEET_REFS}" (at 0.635 0.635 0)
      (effects (font (size 1.27 1.27)) hide)
    )
  )
  (global_label "SYS_PWROK" (shape input) (at 224.79 204.47 180) (fields_autoplaced)
    (effects (font (size 1.27 1.27)) (justify right))
    (property "Intersheetrefs" "${INTERSHEET_REFS}" (at 0.635 0.635 0)
      (effects (font (size 1.27 1.27)) hide)
    )
  )
  (global_label "NCSI_TXD1" (shape input) (at 86.36 251.46 180) (fields_autoplaced)
    (effects (font (size 1.27 1.27)) (justify right))
    (property "Intersheetrefs" "${INTERSHEET_REFS}" (at 0.635 0 0)
      (effects (font (size 1.27 1.27)) hide)
    )
  )
  (global_label "NCSI_RXD1" (shape input) (at 86.36 256.54 180) (fields_autoplaced)
    (effects (font (size 1.27 1.27)) (justify right))
    (property "Intersheetrefs" "${INTERSHEET_REFS}" (at 0.635 0 0)
      (effects (font (size 1.27 1.27)) hide)
    )
  )
  (global_label "ESPI_CLK" (shape input) (at 166.37 105.41 180) (fields_autoplaced)
    (effects (font (size 1.27 1.27)) (justify right))
    (property "Intersheetrefs" "${INTERSHEET_REFS}" (at 0 0.635 0)
      (effects (font (size 1.27 1.27)) hide)
    )
  )
  (global_label "ROT_QSPI_DQ1" (shape input) (at 135.89 231.14 180) (fields_autoplaced)
    (effects (font (size 1.27 1.27)) (justify right))
    (property "Intersheetrefs" "${INTERSHEET_REFS}" (at -6.985 0.635 0)
      (effects (font (size 1.27 1.27)) hide)
    )
  )
  (global_label "VCC3V3" (shape input) (at 91.44 29.21 180) (fields_autoplaced)
    (effects (font (size 1.27 1.27)) (justify right))
    (property "Intersheetrefs" "${INTERSHEET_REFS}" (at -8.89 3.81 0)
      (effects (font (size 1.27 1.27)) hide)
    )
  )
  (global_label "I2C[11]_SDA" (shape input) (at 102.87 95.25 180) (fields_autoplaced)
    (effects (font (size 1.27 1.27)) (justify right))
    (property "Intersheetrefs" "${INTERSHEET_REFS}" (at 0.635 0.635 0)
      (effects (font (size 1.27 1.27)) hide)
    )
  )
  (global_label "VCC1V8" (shape input) (at 154.94 29.21 180) (fields_autoplaced)
    (effects (font (size 1.27 1.27)) (justify right))
    (property "Intersheetrefs" "${INTERSHEET_REFS}" (at -8.255 3.81 0)
      (effects (font (size 1.27 1.27)) hide)
    )
  )
  (global_label "NCSI_CRS_DV" (shape input) (at 86.36 220.98 180) (fields_autoplaced)
    (effects (font (size 1.27 1.27)) (justify right))
    (property "Intersheetrefs" "${INTERSHEET_REFS}" (at 6.35 0 0)
      (effects (font (size 1.27 1.27)) hide)
    )
  )
  (global_label "ESPI_CS1_N" (shape input) (at 166.37 128.27 180) (fields_autoplaced)
    (effects (font (size 1.27 1.27)) (justify right))
    (property "Intersheetrefs" "${INTERSHEET_REFS}" (at 0 0.635 0)
      (effects (font (size 1.27 1.27)) hide)
    )
  )
  (global_label "USR_LED0" (shape input) (at 102.87 158.75 180) (fields_autoplaced)
    (effects (font (size 1.27 1.27)) (justify right))
    (property "Intersheetrefs" "${INTERSHEET_REFS}" (at 0.635 0.635 0)
      (effects (font (size 1.27 1.27)) hide)
    )
  )
  (global_label "NCSI_TXEN" (shape input) (at 86.36 215.9 180) (fields_autoplaced)
    (effects (font (size 1.27 1.27)) (justify right))
    (property "Intersheetrefs" "${INTERSHEET_REFS}" (at 5.715 0 0)
      (effects (font (size 1.27 1.27)) hide)
    )
  )
  (global_label "I3C[3]_SCL_3V3" (shape input) (at 104.14 143.51 180) (fields_autoplaced)
    (effects (font (size 1.27 1.27)) (justify right))
    (property "Intersheetrefs" "${INTERSHEET_REFS}" (at 0.635 0.635 0)
      (effects (font (size 1.27 1.27)) hide)
    )
  )
  (global_label "DDR3_DQ1" (shape bidirectional) (at 294.64 167.64 180) (fields_autoplaced)
    (effects (font (size 1.27 1.27)) (justify right))
    (property "Intersheetrefs" "${INTERSHEET_REFS}" (at 0 0 0)
      (effects (font (size 1.27 1.27)) hide)
    )
  )
  (global_label "MMC_DAT3" (shape input) (at 353.06 154.94 180) (fields_autoplaced)
    (effects (font (size 1.27 1.27)) (justify right))
    (property "Intersheetrefs" "${INTERSHEET_REFS}" (at 0 0.635 0)
      (effects (font (size 1.27 1.27)) hide)
    )
  )
  (global_label "UART0_SCM_RX" (shape input) (at 102.87 80.01 180) (fields_autoplaced)
    (effects (font (size 1.27 1.27)) (justify right))
    (property "Intersheetrefs" "${INTERSHEET_REFS}" (at 0.635 0.635 0)
      (effects (font (size 1.27 1.27)) hide)
    )
  )
  (global_label "I3C[3]_SDA_3V3" (shape input) (at 104.14 140.97 180) (fields_autoplaced)
    (effects (font (size 1.27 1.27)) (justify right))
    (property "Intersheetrefs" "${INTERSHEET_REFS}" (at 0.635 0.635 0)
      (effects (font (size 1.27 1.27)) hide)
    )
  )
  (global_label "VCC3V3" (shape input) (at 154.94 190.5 180) (fields_autoplaced)
    (effects (font (size 1.27 1.27)) (justify right))
    (property "Intersheetrefs" "${INTERSHEET_REFS}" (at 0 0 0)
      (effects (font (size 1.27 1.27)) hide)
    )
  )
  (global_label "RGMII_REF_CLK" (shape input) (at 39.37 59.69 180) (fields_autoplaced)
    (effects (font (size 1.27 1.27)) (justify right))
    (property "Intersheetrefs" "${INTERSHEET_REFS}" (at 0.635 0.635 0)
      (effects (font (size 1.27 1.27)) hide)
    )
  )
  (global_label "ROT_SS" (shape input) (at 361.95 83.82 180) (fields_autoplaced)
    (effects (font (size 1.27 1.27)) (justify right))
    (property "Intersheetrefs" "${INTERSHEET_REFS}" (at 0.635 0.635 0)
      (effects (font (size 1.27 1.27)) hide)
    )
  )
  (global_label "I2C[1]_SDA" (shape input) (at 102.87 113.03 180) (fields_autoplaced)
    (effects (font (size 1.27 1.27)) (justify right))
    (property "Intersheetrefs" "${INTERSHEET_REFS}" (at 0.635 0.635 0)
      (effects (font (size 1.27 1.27)) hide)
    )
  )
  (global_label "RGMII_RXD1" (shape input) (at 39.37 74.93 180) (fields_autoplaced)
    (effects (font (size 1.27 1.27)) (justify right))
    (property "Intersheetrefs" "${INTERSHEET_REFS}" (at 0.635 0.635 0)
      (effects (font (size 1.27 1.27)) hide)
    )
  )
  (global_label "ROT_GPIO2" (shape input) (at 361.95 81.28 180) (fields_autoplaced)
    (effects (font (size 1.27 1.27)) (justify right))
    (property "Intersheetrefs" "${INTERSHEET_REFS}" (at 0.635 0.635 0)
      (effects (font (size 1.27 1.27)) hide)
    )
  )
  (global_label "ULPI1_D5" (shape input) (at 233.68 151.13 180) (fields_autoplaced)
    (effects (font (size 1.27 1.27)) (justify right))
    (property "Intersheetrefs" "${INTERSHEET_REFS}" (at 0.635 0.635 0)
      (effects (font (size 1.27 1.27)) hide)
    )
  )
  (global_label "VCC3V3" (shape input) (at 351.79 27.94 180) (fields_autoplaced)
    (effects (font (size 1.27 1.27)) (justify right))
    (property "Intersheetrefs" "${INTERSHEET_REFS}" (at -3.81 3.81 0)
      (effects (font (size 1.27 1.27)) hide)
    )
  )
  (global_label "ULPI1_D7" (shape input) (at 233.68 156.21 180) (fields_autoplaced)
    (effects (font (size 1.27 1.27)) (justify right))
    (property "Intersheetrefs" "${INTERSHEET_REFS}" (at 0.635 0.635 0)
      (effects (font (size 1.27 1.27)) hide)
    )
  )
  (global_label "DDR3_A12" (shape output) (at 294.64 81.28 180) (fields_autoplaced)
    (effects (font (size 1.27 1.27)) (justify right))
    (property "Intersheetrefs" "${INTERSHEET_REFS}" (at 0 0 0)
      (effects (font (size 1.27 1.27)) hide)
    )
  )
  (global_label "INIT_N" (shape input) (at 135.89 251.46 180) (fields_autoplaced)
    (effects (font (size 1.27 1.27)) (justify right))
    (property "Intersheetrefs" "${INTERSHEET_REFS}" (at -3.175 0.635 0)
      (effects (font (size 1.27 1.27)) hide)
    )
  )
  (global_label "DDR3_DQS1+" (shape bidirectional) (at 294.64 198.12 180) (fields_autoplaced)
    (effects (font (size 1.27 1.27)) (justify right))
    (property "Intersheetrefs" "${INTERSHEET_REFS}" (at 0 0 0)
      (effects (font (size 1.27 1.27)) hide)
    )
  )
  (global_label "I2C[11]_SCL" (shape input) (at 102.87 82.55 180) (fields_autoplaced)
    (effects (font (size 1.27 1.27)) (justify right))
    (property "Intersheetrefs" "${INTERSHEET_REFS}" (at 0.635 0.635 0)
      (effects (font (size 1.27 1.27)) hide)
    )
  )
  (global_label "SPARE1" (shape input) (at 224.79 186.69 180) (fields_autoplaced)
    (effects (font (size 1.27 1.27)) (justify right))
    (property "Intersheetrefs" "${INTERSHEET_REFS}" (at 0.635 0.635 0)
      (effects (font (size 1.27 1.27)) hide)
    )
  )
  (global_label "ESPI_CS0_N" (shape input) (at 166.37 107.95 180) (fields_autoplaced)
    (effects (font (size 1.27 1.27)) (justify right))
    (property "Intersheetrefs" "${INTERSHEET_REFS}" (at 0 0.635 0)
      (effects (font (size 1.27 1.27)) hide)
    )
  )
  (global_label "ULPI1_NXT" (shape input) (at 233.68 166.37 180) (fields_autoplaced)
    (effects (font (size 1.27 1.27)) (justify right))
    (property "Intersheetrefs" "${INTERSHEET_REFS}" (at 0.635 0.635 0)
      (effects (font (size 1.27 1.27)) hide)
    )
  )
  (global_label "ESPI_IO1" (shape input) (at 166.37 115.57 180) (fields_autoplaced)
    (effects (font (size 1.27 1.27)) (justify right))
    (property "Intersheetrefs" "${INTERSHEET_REFS}" (at 0 0.635 0)
      (effects (font (size 1.27 1.27)) hide)
    )
  )
  (global_label "I2C[10]_SDA" (shape input) (at 102.87 130.81 180) (fields_autoplaced)
    (effects (font (size 1.27 1.27)) (justify right))
    (property "Intersheetrefs" "${INTERSHEET_REFS}" (at 0.635 0.635 0)
      (effects (font (size 1.27 1.27)) hide)
    )
  )
  (global_label "UART0_SCM_TX" (shape input) (at 102.87 97.79 180) (fields_autoplaced)
    (effects (font (size 1.27 1.27)) (justify right))
    (property "Intersheetrefs" "${INTERSHEET_REFS}" (at 0.635 0.635 0)
      (effects (font (size 1.27 1.27)) hide)
    )
  )
  (global_label "PP" (shape input) (at 48.26 181.61 180) (fields_autoplaced)
    (effects (font (size 1.27 1.27)) (justify right))
    (property "Intersheetrefs" "${INTERSHEET_REFS}" (at 0 0.635 0)
      (effects (font (size 1.27 1.27)) hide)
    )
  )
  (global_label "DDR3_A13" (shape output) (at 294.64 78.74 180) (fields_autoplaced)
    (effects (font (size 1.27 1.27)) (justify right))
    (property "Intersheetrefs" "${INTERSHEET_REFS}" (at 0 0 0)
      (effects (font (size 1.27 1.27)) hide)
    )
  )
  (global_label "DDR3_DQ2" (shape bidirectional) (at 294.64 147.32 180) (fields_autoplaced)
    (effects (font (size 1.27 1.27)) (justify right))
    (property "Intersheetrefs" "${INTERSHEET_REFS}" (at 0 0 0)
      (effects (font (size 1.27 1.27)) hide)
    )
  )
  (global_label "DDR3_BA2" (shape output) (at 294.64 144.78 180) (fields_autoplaced)
    (effects (font (size 1.27 1.27)) (justify right))
    (property "Intersheetrefs" "${INTERSHEET_REFS}" (at 0 0 0)
      (effects (font (size 1.27 1.27)) hide)
    )
  )
  (global_label "SGPIO0_DI" (shape input) (at 86.36 226.06 180) (fields_autoplaced)
    (effects (font (size 1.27 1.27)) (justify right))
    (property "Intersheetrefs" "${INTERSHEET_REFS}" (at 6.35 0 0)
      (effects (font (size 1.27 1.27)) hide)
    )
  )
  (global_label "DDR3_A10" (shape output) (at 294.64 86.36 180) (fields_autoplaced)
    (effects (font (size 1.27 1.27)) (justify right))
    (property "Intersheetrefs" "${INTERSHEET_REFS}" (at 0 0 0)
      (effects (font (size 1.27 1.27)) hide)
    )
  )
  (global_label "DDR3_A1" (shape output) (at 294.64 93.98 180) (fields_autoplaced)
    (effects (font (size 1.27 1.27)) (justify right))
    (property "Intersheetrefs" "${INTERSHEET_REFS}" (at 0 0 0)
      (effects (font (size 1.27 1.27)) hide)
    )
  )
  (global_label "DDR3_A8" (shape output) (at 294.64 58.42 180) (fields_autoplaced)
    (effects (font (size 1.27 1.27)) (justify right))
    (property "Intersheetrefs" "${INTERSHEET_REFS}" (at 0 0 0)
      (effects (font (size 1.27 1.27)) hide)
    )
  )
  (global_label "RGMII_RXD2" (shape input) (at 39.37 77.47 180) (fields_autoplaced)
    (effects (font (size 1.27 1.27)) (justify right))
    (property "Intersheetrefs" "${INTERSHEET_REFS}" (at 0.635 0.635 0)
      (effects (font (size 1.27 1.27)) hide)
    )
  )
  (global_label "I2C[4]_SCL" (shape input) (at 102.87 74.93 180) (fields_autoplaced)
    (effects (font (size 1.27 1.27)) (justify right))
    (property "Intersheetrefs" "${INTERSHEET_REFS}" (at 0.635 0.635 0)
      (effects (font (size 1.27 1.27)) hide)
    )
  )
  (global_label "I2C[9]_SDA" (shape input) (at 102.87 100.33 180) (fields_autoplaced)
    (effects (font (size 1.27 1.27)) (justify right))
    (property "Intersheetrefs" "${INTERSHEET_REFS}" (at 0.635 0.635 0)
      (effects (font (size 1.27 1.27)) hide)
    )
  )
  (global_label "I2C[0]_SCL" (shape input) (at 102.87 85.09 180) (fields_autoplaced)
    (effects (font (size 1.27 1.27)) (justify right))
    (property "Intersheetrefs" "${INTERSHEET_REFS}" (at 0.635 0.635 0)
      (effects (font (size 1.27 1.27)) hide)
    )
  )
  (global_label "ROT_QSPI_DQ0" (shape input) (at 135.89 236.22 180) (fields_autoplaced)
    (effects (font (size 1.27 1.27)) (justify right))
    (property "Intersheetrefs" "${INTERSHEET_REFS}" (at -6.985 0.635 0)
      (effects (font (size 1.27 1.27)) hide)
    )
  )
  (global_label "DDR3_DQ8" (shape bidirectional) (at 294.64 195.58 180) (fields_autoplaced)
    (effects (font (size 1.27 1.27)) (justify right))
    (property "Intersheetrefs" "${INTERSHEET_REFS}" (at 0 0 0)
      (effects (font (size 1.27 1.27)) hide)
    )
  )
  (global_label "SPARE0" (shape input) (at 224.79 191.77 180) (fields_autoplaced)
    (effects (font (size 1.27 1.27)) (justify right))
    (property "Intersheetrefs" "${INTERSHEET_REFS}" (at 0.635 0.635 0)
      (effects (font (size 1.27 1.27)) hide)
    )
  )
  (global_label "DDR3_DQS1-" (shape bidirectional) (at 294.64 203.2 180) (fields_autoplaced)
    (effects (font (size 1.27 1.27)) (justify right))
    (property "Intersheetrefs" "${INTERSHEET_REFS}" (at 0 0 0)
      (effects (font (size 1.27 1.27)) hide)
    )
  )
  (global_label "MMC_DAT0" (shape input) (at 353.06 162.56 180) (fields_autoplaced)
    (effects (font (size 1.27 1.27)) (justify right))
    (property "Intersheetrefs" "${INTERSHEET_REFS}" (at 0 0.635 0)
      (effects (font (size 1.27 1.27)) hide)
    )
  )
  (global_label "PRSNT1_N" (shape input) (at 224.79 207.01 180) (fields_autoplaced)
    (effects (font (size 1.27 1.27)) (justify right))
    (property "Intersheetrefs" "${INTERSHEET_REFS}" (at 0.635 0.635 0)
      (effects (font (size 1.27 1.27)) hide)
    )
  )
  (global_label "QSPI1_CLK" (shape input) (at 86.36 238.76 180) (fields_autoplaced)
    (effects (font (size 1.27 1.27)) (justify right))
    (property "Intersheetrefs" "${INTERSHEET_REFS}" (at 6.35 0 0)
      (effects (font (size 1.27 1.27)) hide)
    )
  )
  (global_label "DDR3_DQ13" (shape bidirectional) (at 294.64 210.82 180) (fields_autoplaced)
    (effects (font (size 1.27 1.27)) (justify right))
    (property "Intersheetrefs" "${INTERSHEET_REFS}" (at 0 0 0)
      (effects (font (size 1.27 1.27)) hide)
    )
  )
  (global_label "I3C[2]_SDA_3V3" (shape input) (at 104.14 148.59 180) (fields_autoplaced)
    (effects (font (size 1.27 1.27)) (justify right))
    (property "Intersheetrefs" "${INTERSHEET_REFS}" (at 0.635 0.635 0)
      (effects (font (size 1.27 1.27)) hide)
    )
  )
  (global_label "QSPI1_D3" (shape input) (at 86.36 269.24 180) (fields_autoplaced)
    (effects (font (size 1.27 1.27)) (justify right))
    (property "Intersheetrefs" "${INTERSHEET_REFS}" (at 0.635 0 0)
      (effects (font (size 1.27 1.27)) hide)
    )
  )
  (global_label "DDR3_RESET" (shape output) (at 295.91 121.92 180) (fields_autoplaced)
    (effects (font (size 1.27 1.27)) (justify right))
    (property "Intersheetrefs" "${INTERSHEET_REFS}" (at 0.635 0 0)
      (effects (font (size 1.27 1.27)) hide)
    )
  )
  (global_label "ROT_SCLK" (shape input) (at 361.95 101.6 180) (fields_autoplaced)
    (effects (font (size 1.27 1.27)) (justify right))
    (property "Intersheetrefs" "${INTERSHEET_REFS}" (at 0.635 0.635 0)
      (effects (font (size 1.27 1.27)) hide)
    )
  )
  (global_label "MMC_DAT2" (shape input) (at 353.06 157.48 180) (fields_autoplaced)
    (effects (font (size 1.27 1.27)) (justify right))
    (property "Intersheetrefs" "${INTERSHEET_REFS}" (at 0 0.635 0)
      (effects (font (size 1.27 1.27)) hide)
    )
  )
  (global_label "RGMII_RX_CLK" (shape input) (at 39.37 64.77 180) (fields_autoplaced)
    (effects (font (size 1.27 1.27)) (justify right))
    (property "Intersheetrefs" "${INTERSHEET_REFS}" (at 0.635 0.635 0)
      (effects (font (size 1.27 1.27)) hide)
    )
  )
  (global_label "HPM_STBY_RDY" (shape input) (at 224.79 115.57 180) (fields_autoplaced)
    (effects (font (size 1.27 1.27)) (justify right))
    (property "Intersheetrefs" "${INTERSHEET_REFS}" (at 0.635 0.635 0)
      (effects (font (size 1.27 1.27)) hide)
    )
  )
  (global_label "MMC_DAT4" (shape input) (at 353.06 152.4 180) (fields_autoplaced)
    (effects (font (size 1.27 1.27)) (justify right))
    (property "Intersheetrefs" "${INTERSHEET_REFS}" (at 0 0.635 0)
      (effects (font (size 1.27 1.27)) hide)
    )
  )
  (global_label "CHASI#" (shape input) (at 224.79 194.31 180) (fields_autoplaced)
    (effects (font (size 1.27 1.27)) (justify right))
    (property "Intersheetrefs" "${INTERSHEET_REFS}" (at 0.635 0.635 0)
      (effects (font (size 1.27 1.27)) hide)
    )
  )
  (global_label "ULPI1_CLKO" (shape input) (at 233.68 217.17 180) (fields_autoplaced)
    (effects (font (size 1.27 1.27)) (justify right))
    (property "Intersheetrefs" "${INTERSHEET_REFS}" (at 0.635 0.635 0)
      (effects (font (size 1.27 1.27)) hide)
    )
  )
  (global_label "DONE" (shape input) (at 135.89 259.08 180) (fields_autoplaced)
    (effects (font (size 1.27 1.27)) (justify right))
    (property "Intersheetrefs" "${INTERSHEET_REFS}" (at -3.175 0.635 0)
      (effects (font (size 1.27 1.27)) hide)
    )
  )
  (global_label "ULPI1_D3" (shape input) (at 233.68 163.83 180) (fields_autoplaced)
    (effects (font (size 1.27 1.27)) (justify right))
    (property "Intersheetrefs" "${INTERSHEET_REFS}" (at 0.635 0.635 0)
      (effects (font (size 1.27 1.27)) hide)
    )
  )
  (global_label "I3C[2]_SCL_3V3" (shape input) (at 104.14 153.67 180) (fields_autoplaced)
    (effects (font (size 1.27 1.27)) (justify right))
    (property "Intersheetrefs" "${INTERSHEET_REFS}" (at 0.635 0.635 0)
      (effects (font (size 1.27 1.27)) hide)
    )
  )
  (global_label "VCC1V35" (shape input) (at 284.48 29.21 180) (fields_autoplaced)
    (effects (font (size 1.27 1.27)) (justify right))
    (property "Intersheetrefs" "${INTERSHEET_REFS}" (at -6.985 4.445 0)
      (effects (font (size 1.27 1.27)) hide)
    )
  )
  (global_label "DDR3_ODT" (shape output) (at 294.64 185.42 180) (fields_autoplaced)
    (effects (font (size 1.27 1.27)) (justify right))
    (property "Intersheetrefs" "${INTERSHEET_REFS}" (at 0 0 0)
      (effects (font (size 1.27 1.27)) hide)
    )
  )
  (global_label "GCLK100" (shape input) (at 392.43 232.41 0) (fields_autoplaced)
    (effects (font (size 1.27 1.27)) (justify left))
    (property "Intersheetrefs" "${INTERSHEET_REFS}" (at 12.065 11.43 0)
      (effects (font (size 1.27 1.27)) hide)
    )
  )
  (global_label "DDR3_RAS" (shape output) (at 294.64 177.8 180) (fields_autoplaced)
    (effects (font (size 1.27 1.27)) (justify right))
    (property "Intersheetrefs" "${INTERSHEET_REFS}" (at 0 0 0)
      (effects (font (size 1.27 1.27)) hide)
    )
  )
  (global_label "DDR3_DQ10" (shape bidirectional) (at 294.64 190.5 180) (fields_autoplaced)
    (effects (font (size 1.27 1.27)) (justify right))
    (property "Intersheetrefs" "${INTERSHEET_REFS}" (at 0 0 0)
      (effects (font (size 1.27 1.27)) hide)
    )
  )
  (global_label "DDR3_DQS0+" (shape bidirectional) (at 294.64 157.48 180) (fields_autoplaced)
    (effects (font (size 1.27 1.27)) (justify right))
    (property "Intersheetrefs" "${INTERSHEET_REFS}" (at 0 0 0)
      (effects (font (size 1.27 1.27)) hide)
    )
  )
  (global_label "I2C[5]_SDA" (shape input) (at 102.87 57.15 180) (fields_autoplaced)
    (effects (font (size 1.27 1.27)) (justify right))
    (property "Intersheetrefs" "${INTERSHEET_REFS}" (at 0.635 0.635 0)
      (effects (font (size 1.27 1.27)) hide)
    )
  )
  (global_label "DDR3_A5" (shape output) (at 294.64 175.26 180) (fields_autoplaced)
    (effects (font (size 1.27 1.27)) (justify right))
    (property "Intersheetrefs" "${INTERSHEET_REFS}" (at 0 0 0)
      (effects (font (size 1.27 1.27)) hide)
    )
  )
  (global_label "ETH_~{RESET}" (shape output) (at 97.79 166.37 180) (fields_autoplaced)
    (effects (font (size 1.27 1.27)) (justify right))
    (property "Intersheetrefs" "${INTERSHEET_REFS}" (at 0 0.635 0)
      (effects (font (size 1.27 1.27)) hide)
    )
  )
  (global_label "I2C[8]_SCL" (shape input) (at 102.87 90.17 180) (fields_autoplaced)
    (effects (font (size 1.27 1.27)) (justify right))
    (property "Intersheetrefs" "${INTERSHEET_REFS}" (at 0.635 0.635 0)
      (effects (font (size 1.27 1.27)) hide)
    )
  )
  (global_label "PRSNT0_N" (shape input) (at 135.89 248.92 180) (fields_autoplaced)
    (effects (font (size 1.27 1.27)) (justify right))
    (property "Intersheetrefs" "${INTERSHEET_REFS}" (at -1.27 0.635 0)
      (effects (font (size 1.27 1.27)) hide)
    )
  )
  (global_label "ULPI2_D5" (shape input) (at 233.68 69.85 180) (fields_autoplaced)
    (effects (font (size 1.27 1.27)) (justify right))
    (property "Intersheetrefs" "${INTERSHEET_REFS}" (at 0.635 0.635 0)
      (effects (font (size 1.27 1.27)) hide)
    )
  )
  (global_label "JTAG_TCK" (shape input) (at 201.93 234.95 180) (fields_autoplaced)
    (effects (font (size 1.27 1.27)) (justify right))
    (property "Intersheetrefs" "${INTERSHEET_REFS}" (at 0.635 0 0)
      (effects (font (size 1.27 1.27)) hide)
    )
  )
  (global_label "RGMII_TX_EN" (shape output) (at 39.37 87.63 180) (fields_autoplaced)
    (effects (font (size 1.27 1.27)) (justify right))
    (property "Intersheetrefs" "${INTERSHEET_REFS}" (at 0.635 0.635 0)
      (effects (font (size 1.27 1.27)) hide)
    )
  )
  (global_label "PCIE_BMC_TX_DN" (shape input) (at 201.93 257.81 180) (fields_autoplaced)
    (effects (font (size 1.27 1.27)) (justify right))
    (property "Intersheetrefs" "${INTERSHEET_REFS}" (at 0.635 0.635 0)
      (effects (font (size 1.27 1.27)) hide)
    )
  )
  (global_label "ROT_GPIO1" (shape input) (at 361.95 76.2 180) (fields_autoplaced)
    (effects (font (size 1.27 1.27)) (justify right))
    (property "Intersheetrefs" "${INTERSHEET_REFS}" (at 0.635 0.635 0)
      (effects (font (size 1.27 1.27)) hide)
    )
  )
  (global_label "DDR3_DQ3" (shape bidirectional) (at 294.64 170.18 180) (fields_autoplaced)
    (effects (font (size 1.27 1.27)) (justify right))
    (property "Intersheetrefs" "${INTERSHEET_REFS}" (at 0 0 0)
      (effects (font (size 1.27 1.27)) hide)
    )
  )
  (global_label "I2C[12]_SDA" (shape input) (at 102.87 123.19 180) (fields_autoplaced)
    (effects (font (size 1.27 1.27)) (justify right))
    (property "Intersheetrefs" "${INTERSHEET_REFS}" (at 0.635 0.635 0)
      (effects (font (size 1.27 1.27)) hide)
    )
  )
  (global_label "QSPI1_D2" (shape input) (at 86.36 259.08 180) (fields_autoplaced)
    (effects (font (size 1.27 1.27)) (justify right))
    (property "Intersheetrefs" "${INTERSHEET_REFS}" (at 0.635 0 0)
      (effects (font (size 1.27 1.27)) hide)
    )
  )
  (global_label "ULPI2_STP" (shape input) (at 233.68 133.35 180) (fields_autoplaced)
    (effects (font (size 1.27 1.27)) (justify right))
    (property "Intersheetrefs" "${INTERSHEET_REFS}" (at 0.635 0.635 0)
      (effects (font (size 1.27 1.27)) hide)
    )
  )
  (global_label "ULPI2_D3" (shape input) (at 233.68 72.39 180) (fields_autoplaced)
    (effects (font (size 1.27 1.27)) (justify right))
    (property "Intersheetrefs" "${INTERSHEET_REFS}" (at 0.635 0.635 0)
      (effects (font (size 1.27 1.27)) hide)
    )
  )
  (global_label "VCC3V3" (shape input) (at 367.03 232.41 180) (fields_autoplaced)
    (effects (font (size 1.27 1.27)) (justify right))
    (property "Intersheetrefs" "${INTERSHEET_REFS}" (at 18.415 13.97 0)
      (effects (font (size 1.27 1.27)) hide)
    )
  )
  (global_label "I2C[9]_SCL" (shape input) (at 102.87 115.57 180) (fields_autoplaced)
    (effects (font (size 1.27 1.27)) (justify right))
    (property "Intersheetrefs" "${INTERSHEET_REFS}" (at 0.635 0.635 0)
      (effects (font (size 1.27 1.27)) hide)
    )
  )
  (global_label "I2C[2]_SCL" (shape input) (at 102.87 128.27 180) (fields_autoplaced)
    (effects (font (size 1.27 1.27)) (justify right))
    (property "Intersheetrefs" "${INTERSHEET_REFS}" (at 0.635 0.635 0)
      (effects (font (size 1.27 1.27)) hide)
    )
  )
  (global_label "DDR3_BA0" (shape output) (at 294.64 160.02 180) (fields_autoplaced)
    (effects (font (size 1.27 1.27)) (justify right))
    (property "Intersheetrefs" "${INTERSHEET_REFS}" (at 0 0 0)
      (effects (font (size 1.27 1.27)) hide)
    )
  )
  (global_label "ULPI1_D6" (shape input) (at 233.68 146.05 180) (fields_autoplaced)
    (effects (font (size 1.27 1.27)) (justify right))
    (property "Intersheetrefs" "${INTERSHEET_REFS}" (at 0.635 0.635 0)
      (effects (font (size 1.27 1.27)) hide)
    )
  )
  (global_label "DBP_PRDY_N" (shape input) (at 224.79 153.67 180) (fields_autoplaced)
    (effects (font (size 1.27 1.27)) (justify right))
    (property "Intersheetrefs" "${INTERSHEET_REFS}" (at 0.635 0.635 0)
      (effects (font (size 1.27 1.27)) hide)
    )
  )
  (global_label "I2C[2]_SDA" (shape input) (at 102.87 110.49 180) (fields_autoplaced)
    (effects (font (size 1.27 1.27)) (justify right))
    (property "Intersheetrefs" "${INTERSHEET_REFS}" (at 0.635 0.635 0)
      (effects (font (size 1.27 1.27)) hide)
    )
  )
  (global_label "ULPI2_D4" (shape input) (at 233.68 62.23 180) (fields_autoplaced)
    (effects (font (size 1.27 1.27)) (justify right))
    (property "Intersheetrefs" "${INTERSHEET_REFS}" (at 0.635 0.635 0)
      (effects (font (size 1.27 1.27)) hide)
    )
  )
  (global_label "ULPI2_NXT" (shape input) (at 233.68 148.59 180) (fields_autoplaced)
    (effects (font (size 1.27 1.27)) (justify right))
    (property "Intersheetrefs" "${INTERSHEET_REFS}" (at 0.635 0.635 0)
      (effects (font (size 1.27 1.27)) hide)
    )
  )
  (global_label "DDR3_A0" (shape output) (at 294.64 152.4 180) (fields_autoplaced)
    (effects (font (size 1.27 1.27)) (justify right))
    (property "Intersheetrefs" "${INTERSHEET_REFS}" (at 0 0 0)
      (effects (font (size 1.27 1.27)) hide)
    )
  )
  (global_label "DDR3_CKE" (shape output) (at 294.64 193.04 180) (fields_autoplaced)
    (effects (font (size 1.27 1.27)) (justify right))
    (property "Intersheetrefs" "${INTERSHEET_REFS}" (at 0 0 0)
      (effects (font (size 1.27 1.27)) hide)
    )
  )
  (global_label "PROGRAM_N" (shape input) (at 135.89 256.54 180) (fields_autoplaced)
    (effects (font (size 1.27 1.27)) (justify right))
    (property "Intersheetrefs" "${INTERSHEET_REFS}" (at -3.175 0.635 0)
      (effects (font (size 1.27 1.27)) hide)
    )
  )
  (global_label "SGPIO_RESET_N" (shape input) (at 86.36 228.6 180) (fields_autoplaced)
    (effects (font (size 1.27 1.27)) (justify right))
    (property "Intersheetrefs" "${INTERSHEET_REFS}" (at 6.35 0 0)
      (effects (font (size 1.27 1.27)) hide)
    )
  )
  (global_label "SPI0_CLK" (shape input) (at 135.89 218.44 180) (fields_autoplaced)
    (effects (font (size 1.27 1.27)) (justify right))
    (property "Intersheetrefs" "${INTERSHEET_REFS}" (at 1.905 0.635 0)
      (effects (font (size 1.27 1.27)) hide)
    )
  )
  (global_label "RST_PLTRST_BUF_N" (shape input) (at 224.79 181.61 180) (fields_autoplaced)
    (effects (font (size 1.27 1.27)) (justify right))
    (property "Intersheetrefs" "${INTERSHEET_REFS}" (at 0.635 0.635 0)
      (effects (font (size 1.27 1.27)) hide)
    )
  )
  (global_label "DDR3_A6" (shape output) (at 294.64 68.58 180) (fields_autoplaced)
    (effects (font (size 1.27 1.27)) (justify right))
    (property "Intersheetrefs" "${INTERSHEET_REFS}" (at 0 0 0)
      (effects (font (size 1.27 1.27)) hide)
    )
  )
  (global_label "I2C[4]_SDA" (shape input) (at 102.87 62.23 180) (fields_autoplaced)
    (effects (font (size 1.27 1.27)) (justify right))
    (property "Intersheetrefs" "${INTERSHEET_REFS}" (at 0.635 0.635 0)
      (effects (font (size 1.27 1.27)) hide)
    )
  )
  (global_label "DDR3_DQ12" (shape bidirectional) (at 294.64 182.88 180) (fields_autoplaced)
    (effects (font (size 1.27 1.27)) (justify right))
    (property "Intersheetrefs" "${INTERSHEET_REFS}" (at 0 0 0)
      (effects (font (size 1.27 1.27)) hide)
    )
  )
  (global_label "ESPI_IO2" (shape input) (at 166.37 110.49 180) (fields_autoplaced)
    (effects (font (size 1.27 1.27)) (justify right))
    (property "Intersheetrefs" "${INTERSHEET_REFS}" (at 0 0.635 0)
      (effects (font (size 1.27 1.27)) hide)
    )
  )
  (global_label "MMC_CMD" (shape input) (at 353.06 139.7 180) (fields_autoplaced)
    (effects (font (size 1.27 1.27)) (justify right))
    (property "Intersheetrefs" "${INTERSHEET_REFS}" (at 0 0.635 0)
      (effects (font (size 1.27 1.27)) hide)
    )
  )
  (global_label "RGMII_RXD3" (shape input) (at 39.37 161.29 180) (fields_autoplaced)
    (effects (font (size 1.27 1.27)) (justify right))
    (property "Intersheetrefs" "${INTERSHEET_REFS}" (at 0.635 0.635 0)
      (effects (font (size 1.27 1.27)) hide)
    )
  )
  (global_label "ULPI2_D7" (shape input) (at 233.68 95.25 180) (fields_autoplaced)
    (effects (font (size 1.27 1.27)) (justify right))
    (property "Intersheetrefs" "${INTERSHEET_REFS}" (at 0.635 0.635 0)
      (effects (font (size 1.27 1.27)) hide)
    )
  )
  (global_label "GCLK100" (shape input) (at 353.06 167.64 180) (fields_autoplaced)
    (effects (font (size 1.27 1.27)) (justify right))
    (property "Intersheetrefs" "${INTERSHEET_REFS}" (at 0 0.635 0)
      (effects (font (size 1.27 1.27)) hide)
    )
  )
  (global_label "I2C[1]_SCL" (shape input) (at 102.87 125.73 180) (fields_autoplaced)
    (effects (font (size 1.27 1.27)) (justify right))
    (property "Intersheetrefs" "${INTERSHEET_REFS}" (at 0.635 0.635 0)
      (effects (font (size 1.27 1.27)) hide)
    )
  )
  (global_label "INIT_N" (shape input) (at 21.59 262.89 180) (fields_autoplaced)
    (effects (font (size 1.27 1.27)) (justify right))
    (property "Intersheetrefs" "${INTERSHEET_REFS}" (at 0.635 -15.24 0)
      (effects (font (size 1.27 1.27)) hide)
    )
  )
  (global_label "DDR3_A9" (shape output) (at 294.64 76.2 180) (fields_autoplaced)
    (effects (font (size 1.27 1.27)) (justify right))
    (property "Intersheetrefs" "${INTERSHEET_REFS}" (at 0 0 0)
      (effects (font (size 1.27 1.27)) hide)
    )
  )
  (global_label "JTAG_TDO" (shape input) (at 201.93 232.41 180) (fields_autoplaced)
    (effects (font (size 1.27 1.27)) (justify right))
    (property "Intersheetrefs" "${INTERSHEET_REFS}" (at 0.635 0 0)
      (effects (font (size 1.27 1.27)) hide)
    )
  )
  (global_label "HPM_FW_RECOVERY" (shape input) (at 224.79 110.49 180) (fields_autoplaced)
    (effects (font (size 1.27 1.27)) (justify right))
    (property "Intersheetrefs" "${INTERSHEET_REFS}" (at 0.635 0.635 0)
      (effects (font (size 1.27 1.27)) hide)
    )
  )
  (global_label "ETH_INT_N" (shape input) (at 97.79 163.83 180) (fields_autoplaced)
    (effects (font (size 1.27 1.27)) (justify right))
    (property "Intersheetrefs" "${INTERSHEET_REFS}" (at 0 0.635 0)
      (effects (font (size 1.27 1.27)) hide)
    )
  )
  (global_label "ULPI1_D2" (shape input) (at 233.68 143.51 180) (fields_autoplaced)
    (effects (font (size 1.27 1.27)) (justify right))
    (property "Intersheetrefs" "${INTERSHEET_REFS}" (at 0.635 0.635 0)
      (effects (font (size 1.27 1.27)) hide)
    )
  )
  (global_label "MMC_CLK" (shape input) (at 353.06 170.18 180) (fields_autoplaced)
    (effects (font (size 1.27 1.27)) (justify right))
    (property "Intersheetrefs" "${INTERSHEET_REFS}" (at 0 0.635 0)
      (effects (font (size 1.27 1.27)) hide)
    )
  )
  (global_label "ROT_RX" (shape input) (at 361.95 96.52 180) (fields_autoplaced)
    (effects (font (size 1.27 1.27)) (justify right))
    (property "Intersheetrefs" "${INTERSHEET_REFS}" (at 0.635 0.635 0)
      (effects (font (size 1.27 1.27)) hide)
    )
  )
  (global_label "DDR3_A14" (shape output) (at 294.64 63.5 180) (fields_autoplaced)
    (effects (font (size 1.27 1.27)) (justify right))
    (property "Intersheetrefs" "${INTERSHEET_REFS}" (at 0 0 0)
      (effects (font (size 1.27 1.27)) hide)
    )
  )
  (global_label "NCSI_RXD0" (shape input) (at 86.36 266.7 180) (fields_autoplaced)
    (effects (font (size 1.27 1.27)) (justify right))
    (property "Intersheetrefs" "${INTERSHEET_REFS}" (at 0.635 0 0)
      (effects (font (size 1.27 1.27)) hide)
    )
  )
  (global_label "SGPIO0_DO" (shape input) (at 86.36 218.44 180) (fields_autoplaced)
    (effects (font (size 1.27 1.27)) (justify right))
    (property "Intersheetrefs" "${INTERSHEET_REFS}" (at 6.35 0 0)
      (effects (font (size 1.27 1.27)) hide)
    )
  )
  (global_label "I3C[1]_SDA_3V3" (shape input) (at 104.14 151.13 180) (fields_autoplaced)
    (effects (font (size 1.27 1.27)) (justify right))
    (property "Intersheetrefs" "${INTERSHEET_REFS}" (at 0.635 0.635 0)
      (effects (font (size 1.27 1.27)) hide)
    )
  )
  (global_label "DDR3_WE" (shape output) (at 294.64 180.34 180) (fields_autoplaced)
    (effects (font (size 1.27 1.27)) (justify right))
    (property "Intersheetrefs" "${INTERSHEET_REFS}" (at 0 0 0)
      (effects (font (size 1.27 1.27)) hide)
    )
  )
  (global_label "DDR3_A4" (shape output) (at 294.64 66.04 180) (fields_autoplaced)
    (effects (font (size 1.27 1.27)) (justify right))
    (property "Intersheetrefs" "${INTERSHEET_REFS}" (at 0 0 0)
      (effects (font (size 1.27 1.27)) hide)
    )
  )
  (global_label "QSPI1_D0" (shape input) (at 86.36 243.84 180) (fields_autoplaced)
    (effects (font (size 1.27 1.27)) (justify right))
    (property "Intersheetrefs" "${INTERSHEET_REFS}" (at 6.35 0 0)
      (effects (font (size 1.27 1.27)) hide)
    )
  )
  (global_label "HPM_STBY_RST_N" (shape input) (at 224.79 130.81 180) (fields_autoplaced)
    (effects (font (size 1.27 1.27)) (justify right))
    (property "Intersheetrefs" "${INTERSHEET_REFS}" (at 0.635 0.635 0)
      (effects (font (size 1.27 1.27)) hide)
    )
  )
  (global_label "SGPIO0_CLK" (shape input) (at 86.36 261.62 180) (fields_autoplaced)
    (effects (font (size 1.27 1.27)) (justify right))
    (property "Intersheetrefs" "${INTERSHEET_REFS}" (at 0.635 0 0)
      (effects (font (size 1.27 1.27)) hide)
    )
  )
  (global_label "DDR3_DQ11" (shape bidirectional) (at 294.64 208.28 180) (fields_autoplaced)
    (effects (font (size 1.27 1.27)) (justify right))
    (property "Intersheetrefs" "${INTERSHEET_REFS}" (at 0 0 0)
      (effects (font (size 1.27 1.27)) hide)
    )
  )
  (global_label "DDR3_DQ14" (shape bidirectional) (at 294.64 205.74 180) (fields_autoplaced)
    (effects (font (size 1.27 1.27)) (justify right))
    (property "Intersheetrefs" "${INTERSHEET_REFS}" (at 0 0 0)
      (effects (font (size 1.27 1.27)) hide)
    )
  )
  (global_label "I2C[6]_SDA" (shape input) (at 102.87 67.31 180) (fields_autoplaced)
    (effects (font (size 1.27 1.27)) (justify right))
    (property "Intersheetrefs" "${INTERSHEET_REFS}" (at 0.635 0.635 0)
      (effects (font (size 1.27 1.27)) hide)
    )
  )
  (global_label "ESPI_IO0" (shape input) (at 166.37 113.03 180) (fields_autoplaced)
    (effects (font (size 1.27 1.27)) (justify right))
    (property "Intersheetrefs" "${INTERSHEET_REFS}" (at 0 0.635 0)
      (effects (font (size 1.27 1.27)) hide)
    )
  )
  (global_label "SGPIO1_DO" (shape input) (at 86.36 271.78 180) (fields_autoplaced)
    (effects (font (size 1.27 1.27)) (justify right))
    (property "Intersheetrefs" "${INTERSHEET_REFS}" (at 0.635 0 0)
      (effects (font (size 1.27 1.27)) hide)
    )
  )
  (global_label "SGPIO1_CLK" (shape input) (at 86.36 236.22 180) (fields_autoplaced)
    (effects (font (size 1.27 1.27)) (justify right))
    (property "Intersheetrefs" "${INTERSHEET_REFS}" (at 6.35 0 0)
      (effects (font (size 1.27 1.27)) hide)
    )
  )
  (global_label "RGMII_RXD0" (shape input) (at 39.37 67.31 180) (fields_autoplaced)
    (effects (font (size 1.27 1.27)) (justify right))
    (property "Intersheetrefs" "${INTERSHEET_REFS}" (at 0.635 0.635 0)
      (effects (font (size 1.27 1.27)) hide)
    )
  )
  (global_label "UART1_SCM_TX" (shape input) (at 102.87 120.65 180) (fields_autoplaced)
    (effects (font (size 1.27 1.27)) (justify right))
    (property "Intersheetrefs" "${INTERSHEET_REFS}" (at 0.635 0.635 0)
      (effects (font (size 1.27 1.27)) hide)
    )
  )
  (global_label "QSPI1_D1" (shape input) (at 86.36 248.92 180) (fields_autoplaced)
    (effects (font (size 1.27 1.27)) (justify right))
    (property "Intersheetrefs" "${INTERSHEET_REFS}" (at 0.635 0 0)
      (effects (font (size 1.27 1.27)) hide)
    )
  )
  (global_label "DDR3_CLK-" (shape output) (at 294.64 60.96 180) (fields_autoplaced)
    (effects (font (size 1.27 1.27)) (justify right))
    (property "Intersheetrefs" "${INTERSHEET_REFS}" (at 0 0 0)
      (effects (font (size 1.27 1.27)) hide)
    )
  )
  (global_label "ULPI2_RESET" (shape input) (at 233.68 80.01 180) (fields_autoplaced)
    (effects (font (size 1.27 1.27)) (justify right))
    (property "Intersheetrefs" "${INTERSHEET_REFS}" (at 0.635 0.635 0)
      (effects (font (size 1.27 1.27)) hide)
    )
  )
  (global_label "ESPI_IO3" (shape input) (at 166.37 125.73 180) (fields_autoplaced)
    (effects (font (size 1.27 1.27)) (justify right))
    (property "Intersheetrefs" "${INTERSHEET_REFS}" (at 0 0.635 0)
      (effects (font (size 1.27 1.27)) hide)
    )
  )
  (global_label "PCIE_BMC_RX_DN" (shape input) (at 228.6 262.89 180) (fields_autoplaced)
    (effects (font (size 1.27 1.27)) (justify right))
    (property "Intersheetrefs" "${INTERSHEET_REFS}" (at 0.635 0.635 0)
      (effects (font (size 1.27 1.27)) hide)
    )
  )
  (global_label "DDR3_DQ4" (shape bidirectional) (at 294.64 149.86 180) (fields_autoplaced)
    (effects (font (size 1.27 1.27)) (justify right))
    (property "Intersheetrefs" "${INTERSHEET_REFS}" (at 0 0 0)
      (effects (font (size 1.27 1.27)) hide)
    )
  )
  (global_label "I2C[7]_SDA" (shape input) (at 102.87 92.71 180) (fields_autoplaced)
    (effects (font (size 1.27 1.27)) (justify right))
    (property "Intersheetrefs" "${INTERSHEET_REFS}" (at 0.635 0.635 0)
      (effects (font (size 1.27 1.27)) hide)
    )
  )
  (global_label "I2C[3]_SDA" (shape input) (at 102.87 102.87 180) (fields_autoplaced)
    (effects (font (size 1.27 1.27)) (justify right))
    (property "Intersheetrefs" "${INTERSHEET_REFS}" (at 0.635 0.635 0)
      (effects (font (size 1.27 1.27)) hide)
    )
  )
  (global_label "I2C[3]_SCL" (shape input) (at 102.87 87.63 180) (fields_autoplaced)
    (effects (font (size 1.27 1.27)) (justify right))
    (property "Intersheetrefs" "${INTERSHEET_REFS}" (at 0.635 0.635 0)
      (effects (font (size 1.27 1.27)) hide)
    )
  )
  (global_label "HPM_STBY_EN" (shape input) (at 224.79 90.17 180) (fields_autoplaced)
    (effects (font (size 1.27 1.27)) (justify right))
    (property "Intersheetrefs" "${INTERSHEET_REFS}" (at 0.635 0.635 0)
      (effects (font (size 1.27 1.27)) hide)
    )
  )
  (global_label "DDR3_CLK+" (shape output) (at 294.64 55.88 180) (fields_autoplaced)
    (effects (font (size 1.27 1.27)) (justify right))
    (property "Intersheetrefs" "${INTERSHEET_REFS}" (at 0 0 0)
      (effects (font (size 1.27 1.27)) hide)
    )
  )
  (global_label "UART1_SCM_RX" (shape input) (at 102.87 107.95 180) (fields_autoplaced)
    (effects (font (size 1.27 1.27)) (justify right))
    (property "Intersheetrefs" "${INTERSHEET_REFS}" (at 0.635 0.635 0)
      (effects (font (size 1.27 1.27)) hide)
    )
  )
  (global_label "SPI0_MISO" (shape input) (at 135.89 220.98 180) (fields_autoplaced)
    (effects (font (size 1.27 1.27)) (justify right))
    (property "Intersheetrefs" "${INTERSHEET_REFS}" (at 1.905 0.635 0)
      (effects (font (size 1.27 1.27)) hide)
    )
  )
  (global_label "ULPI1_STP" (shape input) (at 233.68 161.29 180) (fields_autoplaced)
    (effects (font (size 1.27 1.27)) (justify right))
    (property "Intersheetrefs" "${INTERSHEET_REFS}" (at 0.635 0.635 0)
      (effects (font (size 1.27 1.27)) hide)
    )
  )
  (global_label "ULPI2_D6" (shape input) (at 233.68 64.77 180) (fields_autoplaced)
    (effects (font (size 1.27 1.27)) (justify right))
    (property "Intersheetrefs" "${INTERSHEET_REFS}" (at 0.635 0.635 0)
      (effects (font (size 1.27 1.27)) hide)
    )
  )
  (global_label "DONE" (shape input) (at 22.86 232.41 180) (fields_autoplaced)
    (effects (font (size 1.27 1.27)) (justify right))
    (property "Intersheetrefs" "${INTERSHEET_REFS}" (at 3.175 -5.08 0)
      (effects (font (size 1.27 1.27)) hide)
    )
  )
  (global_label "DBP_PREQ_N" (shape input) (at 224.79 201.93 180) (fields_autoplaced)
    (effects (font (size 1.27 1.27)) (justify right))
    (property "Intersheetrefs" "${INTERSHEET_REFS}" (at 0.635 0.635 0)
      (effects (font (size 1.27 1.27)) hide)
    )
  )
  (global_label "ULPI2_D0" (shape input) (at 233.68 57.15 180) (fields_autoplaced)
    (effects (font (size 1.27 1.27)) (justify right))
    (property "Intersheetrefs" "${INTERSHEET_REFS}" (at 0.635 0.635 0)
      (effects (font (size 1.27 1.27)) hide)
    )
  )
  (global_label "PCIE_BMC_RX_DP" (shape input) (at 228.6 260.35 180) (fields_autoplaced)
    (effects (font (size 1.27 1.27)) (justify right))
    (property "Intersheetrefs" "${INTERSHEET_REFS}" (at 0.635 0.635 0)
      (effects (font (size 1.27 1.27)) hide)
    )
  )
  (global_label "ROT_QSPI_SCK" (shape input) (at 135.89 254 180) (fields_autoplaced)
    (effects (font (size 1.27 1.27)) (justify right))
    (property "Intersheetrefs" "${INTERSHEET_REFS}" (at -3.175 0.635 0)
      (effects (font (size 1.27 1.27)) hide)
    )
  )
  (global_label "VCC3V3" (shape input) (at 95.25 186.69 180) (fields_autoplaced)
    (effects (font (size 1.27 1.27)) (justify right))
    (property "Intersheetrefs" "${INTERSHEET_REFS}" (at 0 0.635 0)
      (effects (font (size 1.27 1.27)) hide)
    )
  )
  (global_label "I2C[10]_SCL" (shape input) (at 102.87 118.11 180) (fields_autoplaced)
    (effects (font (size 1.27 1.27)) (justify right))
    (property "Intersheetrefs" "${INTERSHEET_REFS}" (at 0.635 0.635 0)
      (effects (font (size 1.27 1.27)) hide)
    )
  )
  (global_label "DDR3_A7" (shape output) (at 294.64 83.82 180) (fields_autoplaced)
    (effects (font (size 1.27 1.27)) (justify right))
    (property "Intersheetrefs" "${INTERSHEET_REFS}" (at 0 0 0)
      (effects (font (size 1.27 1.27)) hide)
    )
  )
  (global_label "ULPI1_D4" (shape input) (at 233.68 140.97 180) (fields_autoplaced)
    (effects (font (size 1.27 1.27)) (justify right))
    (property "Intersheetrefs" "${INTERSHEET_REFS}" (at 0.635 0.635 0)
      (effects (font (size 1.27 1.27)) hide)
    )
  )
  (global_label "RGMII_RX_DV" (shape input) (at 39.37 69.85 180) (fields_autoplaced)
    (effects (font (size 1.27 1.27)) (justify right))
    (property "Intersheetrefs" "${INTERSHEET_REFS}" (at 0.635 0.635 0)
      (effects (font (size 1.27 1.27)) hide)
    )
  )
  (global_label "ROT_TX" (shape input) (at 361.95 99.06 180) (fields_autoplaced)
    (effects (font (size 1.27 1.27)) (justify right))
    (property "Intersheetrefs" "${INTERSHEET_REFS}" (at 0.635 0.635 0)
      (effects (font (size 1.27 1.27)) hide)
    )
  )
  (global_label "DDR3_DQ0" (shape bidirectional) (at 294.64 154.94 180) (fields_autoplaced)
    (effects (font (size 1.27 1.27)) (justify right))
    (property "Intersheetrefs" "${INTERSHEET_REFS}" (at 0 0 0)
      (effects (font (size 1.27 1.27)) hide)
    )
  )
  (global_label "RGMII_TXD2" (shape output) (at 39.37 163.83 180) (fields_autoplaced)
    (effects (font (size 1.27 1.27)) (justify right))
    (property "Intersheetrefs" "${INTERSHEET_REFS}" (at 0.635 0.635 0)
      (effects (font (size 1.27 1.27)) hide)
    )
  )
  (global_label "JTAG_TMS" (shape input) (at 201.93 240.03 180) (fields_autoplaced)
    (effects (font (size 1.27 1.27)) (justify right))
    (property "Intersheetrefs" "${INTERSHEET_REFS}" (at 0.635 0 0)
      (effects (font (size 1.27 1.27)) hide)
    )
  )
  (global_label "MMC_DAT6" (shape input) (at 353.06 147.32 180) (fields_autoplaced)
    (effects (font (size 1.27 1.27)) (justify right))
    (property "Intersheetrefs" "${INTERSHEET_REFS}" (at 0 0.635 0)
      (effects (font (size 1.27 1.27)) hide)
    )
  )
  (global_label "USR_LED1" (shape input) (at 102.87 133.35 180) (fields_autoplaced)
    (effects (font (size 1.27 1.27)) (justify right))
    (property "Intersheetrefs" "${INTERSHEET_REFS}" (at 0.635 0.635 0)
      (effects (font (size 1.27 1.27)) hide)
    )
  )
  (global_label "VCC3V3" (shape input) (at 224.79 29.21 180) (fields_autoplaced)
    (effects (font (size 1.27 1.27)) (justify right))
    (property "Intersheetrefs" "${INTERSHEET_REFS}" (at -1.905 3.81 0)
      (effects (font (size 1.27 1.27)) hide)
    )
  )
  (global_label "ROT_RDY\\ROT_GPIO0" (shape input) (at 361.95 88.9 180) (fields_autoplaced)
    (effects (font (size 1.27 1.27)) (justify right))
    (property "Intersheetrefs" "${INTERSHEET_REFS}" (at 0.635 0.635 0)
      (effects (font (size 1.27 1.27)) hide)
    )
  )
  (global_label "PROGRAM_N" (shape input) (at 55.88 264.16 0) (fields_autoplaced)
    (effects (font (size 1.27 1.27)) (justify left))
    (property "Intersheetrefs" "${INTERSHEET_REFS}" (at 69.4596 264.16 0)
      (effects (font (size 1.27 1.27)) (justify left) hide)
    )
  )
  (global_label "ULPI1_D1" (shape input) (at 233.68 138.43 180) (fields_autoplaced)
    (effects (font (size 1.27 1.27)) (justify right))
    (property "Intersheetrefs" "${INTERSHEET_REFS}" (at 0.635 0.635 0)
      (effects (font (size 1.27 1.27)) hide)
    )
  )
  (global_label "DDR3_DQ5" (shape bidirectional) (at 294.64 139.7 180) (fields_autoplaced)
    (effects (font (size 1.27 1.27)) (justify right))
    (property "Intersheetrefs" "${INTERSHEET_REFS}" (at 0 0 0)
      (effects (font (size 1.27 1.27)) hide)
    )
  )
  (global_label "NCSI_TXD0" (shape input) (at 86.36 213.36 180) (fields_autoplaced)
    (effects (font (size 1.27 1.27)) (justify right))
    (property "Intersheetrefs" "${INTERSHEET_REFS}" (at 5.715 0 0)
      (effects (font (size 1.27 1.27)) hide)
    )
  )
  (global_label "ULPI1_RESET" (shape input) (at 233.68 171.45 180) (fields_autoplaced)
    (effects (font (size 1.27 1.27)) (justify right))
    (property "Intersheetrefs" "${INTERSHEET_REFS}" (at 0.635 0.635 0)
      (effects (font (size 1.27 1.27)) hide)
    )
  )
  (global_label "DDR3_VREF" (shape input) (at 273.05 88.9 90) (fields_autoplaced)
    (effects (font (size 1.27 1.27)) (justify left))
    (property "Intersheetrefs" "${INTERSHEET_REFS}" (at 0 0 0)
      (effects (font (size 1.27 1.27)) hide)
    )
  )
  (global_label "VCC3V3" (shape input) (at 52.07 207.01 0) (fields_autoplaced)
    (effects (font (size 1.27 1.27)) (justify left))
    (property "Intersheetrefs" "${INTERSHEET_REFS}" (at 4.445 0 0)
      (effects (font (size 1.27 1.27)) hide)
    )
  )
  (global_label "DDR3_DQ9" (shape bidirectional) (at 294.64 215.9 180) (fields_autoplaced)
    (effects (font (size 1.27 1.27)) (justify right))
    (property "Intersheetrefs" "${INTERSHEET_REFS}" (at 0 0 0)
      (effects (font (size 1.27 1.27)) hide)
    )
  )
  (global_label "RGMII_TXD0" (shape output) (at 39.37 90.17 180) (fields_autoplaced)
    (effects (font (size 1.27 1.27)) (justify right))
    (property "Intersheetrefs" "${INTERSHEET_REFS}" (at 0.635 0.635 0)
      (effects (font (size 1.27 1.27)) hide)
    )
  )
  (global_label "RoT_CPU_RST_N" (shape input) (at 224.79 189.23 180) (fields_autoplaced)
    (effects (font (size 1.27 1.27)) (justify right))
    (property "Intersheetrefs" "${INTERSHEET_REFS}" (at 0.635 0.635 0)
      (effects (font (size 1.27 1.27)) hide)
    )
  )
  (global_label "ULPI2_D2" (shape input) (at 233.68 59.69 180) (fields_autoplaced)
    (effects (font (size 1.27 1.27)) (justify right))
    (property "Intersheetrefs" "${INTERSHEET_REFS}" (at 0.635 0.635 0)
      (effects (font (size 1.27 1.27)) hide)
    )
  )
  (global_label "PIRQ#" (shape input) (at 48.26 194.31 180) (fields_autoplaced)
    (effects (font (size 1.27 1.27)) (justify right))
    (property "Intersheetrefs" "${INTERSHEET_REFS}" (at 0 0.635 0)
      (effects (font (size 1.27 1.27)) hide)
    )
  )
  (global_label "DDR3_DQ6" (shape bidirectional) (at 294.64 142.24 180) (fields_autoplaced)
    (effects (font (size 1.27 1.27)) (justify right))
    (property "Intersheetrefs" "${INTERSHEET_REFS}" (at 0 0 0)
      (effects (font (size 1.27 1.27)) hide)
    )
  )
  (global_label "ULPI1_D0" (shape input) (at 233.68 85.09 180) (fields_autoplaced)
    (effects (font (size 1.27 1.27)) (justify right))
    (property "Intersheetrefs" "${INTERSHEET_REFS}" (at 0.635 0.635 0)
      (effects (font (size 1.27 1.27)) hide)
    )
  )
  (global_label "NCSI_CLK" (shape input) (at 86.36 246.38 180) (fields_autoplaced)
    (effects (font (size 1.27 1.27)) (justify right))
    (property "Intersheetrefs" "${INTERSHEET_REFS}" (at 6.35 0 0)
      (effects (font (size 1.27 1.27)) hide)
    )
  )
  (global_label "ESPI_ALERT_N" (shape input) (at 166.37 118.11 180) (fields_autoplaced)
    (effects (font (size 1.27 1.27)) (justify right))
    (property "Intersheetrefs" "${INTERSHEET_REFS}" (at 0 0.635 0)
      (effects (font (size 1.27 1.27)) hide)
    )
  )
  (global_label "SPI0_MOSI" (shape input) (at 135.89 226.06 180) (fields_autoplaced)
    (effects (font (size 1.27 1.27)) (justify right))
    (property "Intersheetrefs" "${INTERSHEET_REFS}" (at 1.905 0.635 0)
      (effects (font (size 1.27 1.27)) hide)
    )
  )
  (global_label "SGPIO0_LD" (shape input) (at 86.36 231.14 180) (fields_autoplaced)
    (effects (font (size 1.27 1.27)) (justify right))
    (property "Intersheetrefs" "${INTERSHEET_REFS}" (at 6.35 0 0)
      (effects (font (size 1.27 1.27)) hide)
    )
  )
  (global_label "I3C[1]_SCL_3V3" (shape input) (at 104.14 138.43 180) (fields_autoplaced)
    (effects (font (size 1.27 1.27)) (justify right))
    (property "Intersheetrefs" "${INTERSHEET_REFS}" (at 0.635 0.635 0)
      (effects (font (size 1.27 1.27)) hide)
    )
  )
  (global_label "CLK_100M_PCIE_DN" (shape input) (at 228.6 278.13 180) (fields_autoplaced)
    (effects (font (size 1.27 1.27)) (justify right))
    (property "Intersheetrefs" "${INTERSHEET_REFS}" (at 0.635 0.635 0)
      (effects (font (size 1.27 1.27)) hide)
    )
  )
  (global_label "DDR3_A3" (shape output) (at 294.64 172.72 180) (fields_autoplaced)
    (effects (font (size 1.27 1.27)) (justify right))
    (property "Intersheetrefs" "${INTERSHEET_REFS}" (at 0 0 0)
      (effects (font (size 1.27 1.27)) hide)
    )
  )
  (global_label "DDR3_BA1" (shape output) (at 294.64 88.9 180) (fields_autoplaced)
    (effects (font (size 1.27 1.27)) (justify right))
    (property "Intersheetrefs" "${INTERSHEET_REFS}" (at 0 0 0)
      (effects (font (size 1.27 1.27)) hide)
    )
  )
  (global_label "VIRTUAL_RESEAT" (shape input) (at 135.89 246.38 180) (fields_autoplaced)
    (effects (font (size 1.27 1.27)) (justify right))
    (property "Intersheetrefs" "${INTERSHEET_REFS}" (at -1.27 0.635 0)
      (effects (font (size 1.27 1.27)) hide)
    )
  )
  (global_label "MMC_DAT5" (shape input) (at 353.06 149.86 180) (fields_autoplaced)
    (effects (font (size 1.27 1.27)) (justify right))
    (property "Intersheetrefs" "${INTERSHEET_REFS}" (at 0 0.635 0)
      (effects (font (size 1.27 1.27)) hide)
    )
  )
  (global_label "ULPI_DIR" (shape input) (at 233.68 125.73 180) (fields_autoplaced)
    (effects (font (size 1.27 1.27)) (justify right))
    (property "Intersheetrefs" "${INTERSHEET_REFS}" (at 0.635 0.635 0)
      (effects (font (size 1.27 1.27)) hide)
    )
  )
  (global_label "DDR3_CS" (shape output) (at 294.64 116.84 180) (fields_autoplaced)
    (effects (font (size 1.27 1.27)) (justify right))
    (property "Intersheetrefs" "${INTERSHEET_REFS}" (at 0 0 0)
      (effects (font (size 1.27 1.27)) hide)
    )
  )
  (global_label "DDR3_DM1" (shape bidirectional) (at 294.64 200.66 180) (fields_autoplaced)
    (effects (font (size 1.27 1.27)) (justify right))
    (property "Intersheetrefs" "${INTERSHEET_REFS}" (at 0 0 0)
      (effects (font (size 1.27 1.27)) hide)
    )
  )
  (global_label "ULPI2_CLKO" (shape input) (at 233.68 214.63 180) (fields_autoplaced)
    (effects (font (size 1.27 1.27)) (justify right))
    (property "Intersheetrefs" "${INTERSHEET_REFS}" (at 0.635 0.635 0)
      (effects (font (size 1.27 1.27)) hide)
    )
  )
  (global_label "ULPI1_DIR" (shape input) (at 233.68 176.53 180) (fields_autoplaced)
    (effects (font (size 1.27 1.27)) (justify right))
    (property "Intersheetrefs" "${INTERSHEET_REFS}" (at 0.635 0.635 0)
      (effects (font (size 1.27 1.27)) hide)
    )
  )
  (global_label "SYS_PWRBTN_N" (shape input) (at 224.79 199.39 180) (fields_autoplaced)
    (effects (font (size 1.27 1.27)) (justify right))
    (property "Intersheetrefs" "${INTERSHEET_REFS}" (at 0.635 0.635 0)
      (effects (font (size 1.27 1.27)) hide)
    )
  )
  (global_label "DDR3_DQ7" (shape bidirectional) (at 294.64 137.16 180) (fields_autoplaced)
    (effects (font (size 1.27 1.27)) (justify right))
    (property "Intersheetrefs" "${INTERSHEET_REFS}" (at 0 0 0)
      (effects (font (size 1.27 1.27)) hide)
    )
  )
  (global_label "CLK_100M_PCIE_DP" (shape input) (at 228.6 275.59 180) (fields_autoplaced)
    (effects (font (size 1.27 1.27)) (justify right))
    (property "Intersheetrefs" "${INTERSHEET_REFS}" (at 0.635 0.635 0)
      (effects (font (size 1.27 1.27)) hide)
    )
  )
  (global_label "ETH_MDIO" (shape bidirectional) (at 39.37 57.15 180) (fields_autoplaced)
    (effects (font (size 1.27 1.27)) (justify right))
    (property "Intersheetrefs" "${INTERSHEET_REFS}" (at 0.635 0.635 0)
      (effects (font (size 1.27 1.27)) hide)
    )
  )
  (global_label "I3C[0]_SDA_3V3" (shape input) (at 104.14 156.21 180) (fields_autoplaced)
    (effects (font (size 1.27 1.27)) (justify right))
    (property "Intersheetrefs" "${INTERSHEET_REFS}" (at 0.635 0.635 0)
      (effects (font (size 1.27 1.27)) hide)
    )
  )
  (global_label "I2C[12]_SCL" (shape input) (at 102.87 105.41 180) (fields_autoplaced)
    (effects (font (size 1.27 1.27)) (justify right))
    (property "Intersheetrefs" "${INTERSHEET_REFS}" (at 0.635 0.635 0)
      (effects (font (size 1.27 1.27)) hide)
    )
  )
  (global_label "ROT_QSPI_DQ3" (shape input) (at 135.89 228.6 180) (fields_autoplaced)
    (effects (font (size 1.27 1.27)) (justify right))
    (property "Intersheetrefs" "${INTERSHEET_REFS}" (at -6.985 0.635 0)
      (effects (font (size 1.27 1.27)) hide)
    )
  )
  (global_label "PCIE_BMC_TX_DP" (shape input) (at 201.93 255.27 180) (fields_autoplaced)
    (effects (font (size 1.27 1.27)) (justify right))
    (property "Intersheetrefs" "${INTERSHEET_REFS}" (at 0.635 0.635 0)
      (effects (font (size 1.27 1.27)) hide)
    )
  )
  (global_label "RGMII_TXD1" (shape output) (at 39.37 158.75 180) (fields_autoplaced)
    (effects (font (size 1.27 1.27)) (justify right))
    (property "Intersheetrefs" "${INTERSHEET_REFS}" (at 0.635 0.635 0)
      (effects (font (size 1.27 1.27)) hide)
    )
  )
  (global_label "RGMII_TXD3" (shape input) (at 39.37 166.37 180) (fields_autoplaced)
    (effects (font (size 1.27 1.27)) (justify right))
    (property "Intersheetrefs" "${INTERSHEET_REFS}" (at 0.635 0.635 0)
      (effects (font (size 1.27 1.27)) hide)
    )
  )
  (global_label "IRQ_N" (shape input) (at 224.79 196.85 180) (fields_autoplaced)
    (effects (font (size 1.27 1.27)) (justify right))
    (property "Intersheetrefs" "${INTERSHEET_REFS}" (at 0.635 0.635 0)
      (effects (font (size 1.27 1.27)) hide)
    )
  )
  (global_label "MMC_RSTN" (shape input) (at 353.06 132.08 180) (fields_autoplaced)
    (effects (font (size 1.27 1.27)) (justify right))
    (property "Intersheetrefs" "${INTERSHEET_REFS}" (at 0 0.635 0)
      (effects (font (size 1.27 1.27)) hide)
    )
  )
  (global_label "QSPI1_CS0_N" (shape input) (at 86.36 223.52 180) (fields_autoplaced)
    (effects (font (size 1.27 1.27)) (justify right))
    (property "Intersheetrefs" "${INTERSHEET_REFS}" (at 6.35 0 0)
      (effects (font (size 1.27 1.27)) hide)
    )
  )
  (global_label "GPIO" (shape input) (at 48.26 186.69 180) (fields_autoplaced)
    (effects (font (size 1.27 1.27)) (justify right))
    (property "Intersheetrefs" "${INTERSHEET_REFS}" (at 0 0.635 0)
      (effects (font (size 1.27 1.27)) hide)
    )
  )
  (global_label "VCC3V3" (shape input) (at 46.99 252.73 180) (fields_autoplaced)
    (effects (font (size 1.27 1.27)) (justify right))
    (property "Intersheetrefs" "${INTERSHEET_REFS}" (at 37.5228 252.73 0)
      (effects (font (size 1.27 1.27)) (justify right) hide)
    )
  )
  (global_label "RST" (shape input) (at 48.26 189.23 180) (fields_autoplaced)
    (effects (font (size 1.27 1.27)) (justify right))
    (property "Intersheetrefs" "${INTERSHEET_REFS}" (at 0 0.635 0)
      (effects (font (size 1.27 1.27)) hide)
    )
  )
  (global_label "JTAG_TDI" (shape input) (at 201.93 237.49 180) (fields_autoplaced)
    (effects (font (size 1.27 1.27)) (justify right))
    (property "Intersheetrefs" "${INTERSHEET_REFS}" (at 0.635 0 0)
      (effects (font (size 1.27 1.27)) hide)
    )
  )
  (global_label "NCSI_RXER" (shape input) (at 86.36 254 180) (fields_autoplaced)
    (effects (font (size 1.27 1.27)) (justify right))
    (property "Intersheetrefs" "${INTERSHEET_REFS}" (at 0.635 0 0)
      (effects (font (size 1.27 1.27)) hide)
    )
  )
  (global_label "SPI0_CS_N" (shape input) (at 135.89 223.52 180) (fields_autoplaced)
    (effects (font (size 1.27 1.27)) (justify right))
    (property "Intersheetrefs" "${INTERSHEET_REFS}" (at 1.905 0.635 0)
      (effects (font (size 1.27 1.27)) hide)
    )
  )
  (global_label "ROT_QSPI_CS_N" (shape input) (at 135.89 238.76 180) (fields_autoplaced)
    (effects (font (size 1.27 1.27)) (justify right))
    (property "Intersheetrefs" "${INTERSHEET_REFS}" (at -6.985 0.635 0)
      (effects (font (size 1.27 1.27)) hide)
    )
  )
  (global_label "RGMII_TX_CLK" (shape output) (at 39.37 62.23 180) (fields_autoplaced)
    (effects (font (size 1.27 1.27)) (justify right))
    (property "Intersheetrefs" "${INTERSHEET_REFS}" (at 0.635 0.635 0)
      (effects (font (size 1.27 1.27)) hide)
    )
  )
  (global_label "DDR3_DM0" (shape bidirectional) (at 294.64 165.1 180) (fields_autoplaced)
    (effects (font (size 1.27 1.27)) (justify right))
    (property "Intersheetrefs" "${INTERSHEET_REFS}" (at 0 0 0)
      (effects (font (size 1.27 1.27)) hide)
    )
  )
  (global_label "DDR3_DQ15" (shape bidirectional) (at 294.64 213.36 180) (fields_autoplaced)
    (effects (font (size 1.27 1.27)) (justify right))
    (property "Intersheetrefs" "${INTERSHEET_REFS}" (at 0 0 0)
      (effects (font (size 1.27 1.27)) hide)
    )
  )
  (global_label "I3C[0]_SCL_3V3" (shape input) (at 104.14 146.05 180) (fields_autoplaced)
    (effects (font (size 1.27 1.27)) (justify right))
    (property "Intersheetrefs" "${INTERSHEET_REFS}" (at 0.635 0.635 0)
      (effects (font (size 1.27 1.27)) hide)
    )
  )
  (global_label "MMC_DAT7" (shape input) (at 353.06 144.78 180) (fields_autoplaced)
    (effects (font (size 1.27 1.27)) (justify right))
    (property "Intersheetrefs" "${INTERSHEET_REFS}" (at 0 0.635 0)
      (effects (font (size 1.27 1.27)) hide)
    )
  )
  (global_label "DDR3_DQS0-" (shape bidirectional) (at 294.64 162.56 180) (fields_autoplaced)
    (effects (font (size 1.27 1.27)) (justify right))
    (property "Intersheetrefs" "${INTERSHEET_REFS}" (at 0 0 0)
      (effects (font (size 1.27 1.27)) hide)
    )
  )
  (global_label "DDR3_CAS" (shape output) (at 294.64 187.96 180) (fields_autoplaced)
    (effects (font (size 1.27 1.27)) (justify right))
    (property "Intersheetrefs" "${INTERSHEET_REFS}" (at 0 0 0)
      (effects (font (size 1.27 1.27)) hide)
    )
  )
  (global_label "I2C[0]_SDA" (shape input) (at 102.87 69.85 180) (fields_autoplaced)
    (effects (font (size 1.27 1.27)) (justify right))
    (property "Intersheetrefs" "${INTERSHEET_REFS}" (at 0.635 0.635 0)
      (effects (font (size 1.27 1.27)) hide)
    )
  )
  (global_label "SGPIO1_LD" (shape input) (at 86.36 241.3 180) (fields_autoplaced)
    (effects (font (size 1.27 1.27)) (justify right))
    (property "Intersheetrefs" "${INTERSHEET_REFS}" (at 6.35 0 0)
      (effects (font (size 1.27 1.27)) hide)
    )
  )
  (global_label "VCC3V3" (shape input) (at 24.13 29.21 180) (fields_autoplaced)
    (effects (font (size 1.27 1.27)) (justify right))
    (property "Intersheetrefs" "${INTERSHEET_REFS}" (at -12.7 3.81 0)
      (effects (font (size 1.27 1.27)) hide)
    )
  )
  (global_label "I2C[6]_SCL" (shape input) (at 102.87 64.77 180) (fields_autoplaced)
    (effects (font (size 1.27 1.27)) (justify right))
    (property "Intersheetrefs" "${INTERSHEET_REFS}" (at 0.635 0.635 0)
      (effects (font (size 1.27 1.27)) hide)
    )
  )
  (global_label "MMC_DAT1" (shape input) (at 353.06 160.02 180) (fields_autoplaced)
    (effects (font (size 1.27 1.27)) (justify right))
    (property "Intersheetrefs" "${INTERSHEET_REFS}" (at 0 0.635 0)
      (effects (font (size 1.27 1.27)) hide)
    )
  )
  (global_label "USR_LED2" (shape input) (at 102.87 135.89 180) (fields_autoplaced)
    (effects (font (size 1.27 1.27)) (justify right))
    (property "Intersheetrefs" "${INTERSHEET_REFS}" (at 0.635 0.635 0)
      (effects (font (size 1.27 1.27)) hide)
    )
  )
  (global_label "VCC3V3" (shape input) (at 29.21 247.65 0) (fields_autoplaced)
    (effects (font (size 1.27 1.27)) (justify left))
    (property "Intersheetrefs" "${INTERSHEET_REFS}" (at -4.445 -5.715 0)
      (effects (font (size 1.27 1.27)) hide)
    )
  )
  (global_label "ROT_MISO" (shape input) (at 361.95 93.98 180) (fields_autoplaced)
    (effects (font (size 1.27 1.27)) (justify right))
    (property "Intersheetrefs" "${INTERSHEET_REFS}" (at 0.635 0.635 0)
      (effects (font (size 1.27 1.27)) hide)
    )
  )
  (global_label "I2C[8]_SDA" (shape input) (at 102.87 77.47 180) (fields_autoplaced)
    (effects (font (size 1.27 1.27)) (justify right))
    (property "Intersheetrefs" "${INTERSHEET_REFS}" (at 0.635 0.635 0)
      (effects (font (size 1.27 1.27)) hide)
    )
  )
  (global_label "DDR3_A2" (shape output) (at 294.64 73.66 180) (fields_autoplaced)
    (effects (font (size 1.27 1.27)) (justify right))
    (property "Intersheetrefs" "${INTERSHEET_REFS}" (at 0 0 0)
      (effects (font (size 1.27 1.27)) hide)
    )
  )
  (global_label "SGPIO1_DI" (shape input) (at 86.36 233.68 180) (fields_autoplaced)
    (effects (font (size 1.27 1.27)) (justify right))
    (property "Intersheetrefs" "${INTERSHEET_REFS}" (at 6.35 0 0)
      (effects (font (size 1.27 1.27)) hide)
    )
  )
  (global_label "SGPIO_INTR_N" (shape input) (at 86.36 264.16 180) (fields_autoplaced)
    (effects (font (size 1.27 1.27)) (justify right))
    (property "Intersheetrefs" "${INTERSHEET_REFS}" (at 0.635 0 0)
      (effects (font (size 1.27 1.27)) hide)
    )
  )
  (global_label "DDR3_A11" (shape output) (at 294.64 71.12 180) (fields_autoplaced)
    (effects (font (size 1.27 1.27)) (justify right))
    (property "Intersheetrefs" "${INTERSHEET_REFS}" (at 0 0 0)
      (effects (font (size 1.27 1.27)) hide)
    )
  )
  (global_label "ULPI2_D1" (shape input) (at 233.68 67.31 180) (fields_autoplaced)
    (effects (font (size 1.27 1.27)) (justify right))
    (property "Intersheetrefs" "${INTERSHEET_REFS}" (at 0.635 0.635 0)
      (effects (font (size 1.27 1.27)) hide)
    )
  )
  (global_label "VCC3V3" (shape input) (at 344.17 231.14 180) (fields_autoplaced)
    (effects (font (size 1.27 1.27)) (justify right))
    (property "Intersheetrefs" "${INTERSHEET_REFS}" (at -4.445 12.7 0)
      (effects (font (size 1.27 1.27)) hide)
    )
  )
  (global_label "ROT_MOSI" (shape input) (at 361.95 91.44 180) (fields_autoplaced)
    (effects (font (size 1.27 1.27)) (justify right))
    (property "Intersheetrefs" "${INTERSHEET_REFS}" (at 0.635 0.635 0)
      (effects (font (size 1.27 1.27)) hide)
    )
  )
  (global_label "ROT_QSPI_DQ2" (shape input) (at 135.89 233.68 180) (fields_autoplaced)
    (effects (font (size 1.27 1.27)) (justify right))
    (property "Intersheetrefs" "${INTERSHEET_REFS}" (at -6.985 0.635 0)
      (effects (font (size 1.27 1.27)) hide)
    )
  )
  (global_label "I2C[7]_SCL" (shape input) (at 102.87 72.39 180) (fields_autoplaced)
    (effects (font (size 1.27 1.27)) (justify right))
    (property "Intersheetrefs" "${INTERSHEET_REFS}" (at 0.635 0.635 0)
      (effects (font (size 1.27 1.27)) hide)
    )
  )
  (global_label "ETH_MDC" (shape output) (at 39.37 72.39 180) (fields_autoplaced)
    (effects (font (size 1.27 1.27)) (justify right))
    (property "Intersheetrefs" "${INTERSHEET_REFS}" (at 0.635 0.635 0)
      (effects (font (size 1.27 1.27)) hide)
    )
  )
  (global_label "ESPI_RESET_N" (shape input) (at 166.37 120.65 180) (fields_autoplaced)
    (effects (font (size 1.27 1.27)) (justify right))
    (property "Intersheetrefs" "${INTERSHEET_REFS}" (at 0 0.635 0)
      (effects (font (size 1.27 1.27)) hide)
    )
  )

  (symbol (lib_id "antmicroFPGAChips:ECP5_LFE5UM5G-85") (at 175.26 57.15 0) (unit 4)
    (in_bom yes) (on_board yes) (dnp no) (fields_autoplaced)
    (property "Reference" "U21" (at 189.23 49.53 0)
      (effects (font (size 1.524 1.524)))
    )
    (property "Value" "ECP5UM5G_85_CABGA756" (at 189.23 52.07 0)
      (effects (font (size 1.524 1.524)))
    )
    (property "Footprint" "antmicro-footprints:BGA-1024-756_27x27mm_Layout32x32_P0.8mm" (at 175.26 57.15 0)
      (effects (font (size 1.27 1.27)) hide)
    )
    (property "Datasheet" "https://www.latticesemi.com/-/media/LatticeSemi/Documents/DataSheets/ECP5/FPGA-DS-02012-2-2-ECP5-ECP5G-Family-Data-Sheet.ashx?document_id=50461" (at 175.26 57.15 0)
      (effects (font (size 1.27 1.27)) hide)
    )
    (property "MPN" "LFE5UM5G-85F-8BG756C" (at 179.07 58.42 0)
      (effects (font (size 1.524 1.524)) (justify right) hide)
    )
    (property "Manufacturer" "Lattice Semiconductor" (at 203.962 111.7346 0)
      (effects (font (size 1.27 1.27)) (justify left) hide)
    )
    (property "Author" "Antmicro" (at 252.73 76.2 0)
      (effects (font (size 1.27 1.27) (thickness 0.15)) (justify left bottom) hide)
    )
    (property "License" "Apache-2.0" (at 252.73 78.74 0)
      (effects (font (size 1.27 1.27) (thickness 0.15)) (justify left bottom) hide)
    )
    (pin "AA11")
    (pin "AA12")
    (pin "AA13")
    (pin "AA14")
    (pin "AA15")
    (pin "AA16")
    (pin "AA17")
    (pin "AA18")
    (pin "AA19")
    (pin "AA20")
    (pin "AA21")
    (pin "AA22")
    (pin "AB11")
    (pin "AB12")
    (pin "AB13")
    (pin "AB14")
    (pin "AB15")
    (pin "AB16")
    (pin "AB17")
    (pin "AB18")
    (pin "AB19")
    (pin "AB20")
    (pin "AB21")
    (pin "AB22")
    (pin "AC11")
    (pin "AC12")
    (pin "AC13")
    (pin "AC14")
    (pin "AC15")
    (pin "AC16")
    (pin "AC17")
    (pin "AC18")
    (pin "AC19")
    (pin "AC20")
    (pin "AC21")
    (pin "AC22")
    (pin "AC29")
    (pin "AC4")
    (pin "AD2")
    (pin "AD28")
    (pin "AD31")
    (pin "AD5")
    (pin "AE26")
    (pin "AE7")
    (pin "AF11")
    (pin "AF12")
    (pin "AF14")
    (pin "AF15")
    (pin "AF16")
    (pin "AF17")
    (pin "AF19")
    (pin "AF20")
    (pin "AF22")
    (pin "AF23")
    (pin "AG11")
    (pin "AG12")
    (pin "AG14")
    (pin "AG15")
    (pin "AG16")
    (pin "AG17")
    (pin "AG19")
    (pin "AG2")
    (pin "AG20")
    (pin "AG22")
    (pin "AG23")
    (pin "AG24")
    (pin "AG31")
    (pin "AG9")
    (pin "AH11")
    (pin "AH12")
    (pin "AH14")
    (pin "AH15")
    (pin "AH16")
    (pin "AH17")
    (pin "AH19")
    (pin "AH2")
    (pin "AH20")
    (pin "AH22")
    (pin "AH23")
    (pin "AH24")
    (pin "AH25")
    (pin "AH26")
    (pin "AH29")
    (pin "AH31")
    (pin "AH5")
    (pin "AH7")
    (pin "AH8")
    (pin "AH9")
    (pin "AJ10")
    (pin "AJ11")
    (pin "AJ12")
    (pin "AJ13")
    (pin "AJ14")
    (pin "AJ15")
    (pin "AJ16")
    (pin "AJ17")
    (pin "AJ18")
    (pin "AJ19")
    (pin "AJ20")
    (pin "AJ21")
    (pin "AJ22")
    (pin "AJ23")
    (pin "AJ24")
    (pin "AJ25")
    (pin "AJ26")
    (pin "AJ7")
    (pin "AJ8")
    (pin "AJ9")
    (pin "AK11")
    (pin "AK14")
    (pin "AK15")
    (pin "AK16")
    (pin "AK17")
    (pin "AK20")
    (pin "AK23")
    (pin "AK24")
    (pin "AK25")
    (pin "AK26")
    (pin "AK7")
    (pin "AK8")
    (pin "AL11")
    (pin "AL12")
    (pin "AL14")
    (pin "AL15")
    (pin "AL17")
    (pin "AL18")
    (pin "AL2")
    (pin "AL20")
    (pin "AL21")
    (pin "AL23")
    (pin "AL24")
    (pin "AL26")
    (pin "AL29")
    (pin "AL31")
    (pin "AL5")
    (pin "AL7")
    (pin "AL8")
    (pin "AL9")
    (pin "AM26")
    (pin "AM7")
    (pin "B13")
    (pin "B15")
    (pin "B18")
    (pin "B2")
    (pin "B20")
    (pin "B24")
    (pin "B28")
    (pin "B31")
    (pin "B5")
    (pin "B9")
    (pin "E13")
    (pin "E15")
    (pin "E18")
    (pin "E2")
    (pin "E20")
    (pin "E24")
    (pin "E26")
    (pin "E28")
    (pin "E31")
    (pin "E5")
    (pin "E7")
    (pin "E9")
    (pin "G10")
    (pin "G11")
    (pin "G14")
    (pin "G15")
    (pin "G16")
    (pin "G17")
    (pin "G18")
    (pin "G19")
    (pin "G22")
    (pin "G23")
    (pin "G24")
    (pin "G9")
    (pin "H29")
    (pin "H4")
    (pin "J2")
    (pin "J28")
    (pin "J31")
    (pin "J5")
    (pin "K10")
    (pin "K11")
    (pin "K13")
    (pin "K20")
    (pin "K22")
    (pin "K23")
    (pin "L10")
    (pin "L11")
    (pin "L12")
    (pin "L13")
    (pin "L14")
    (pin "L15")
    (pin "L16")
    (pin "L17")
    (pin "L18")
    (pin "L19")
    (pin "L20")
    (pin "L21")
    (pin "L22")
    (pin "L23")
    (pin "L28")
    (pin "L5")
    (pin "M11")
    (pin "M12")
    (pin "M13")
    (pin "M14")
    (pin "M15")
    (pin "M16")
    (pin "M17")
    (pin "M18")
    (pin "M19")
    (pin "M20")
    (pin "M21")
    (pin "M22")
    (pin "N10")
    (pin "N11")
    (pin "N12")
    (pin "N13")
    (pin "N14")
    (pin "N15")
    (pin "N16")
    (pin "N17")
    (pin "N18")
    (pin "N19")
    (pin "N2")
    (pin "N20")
    (pin "N21")
    (pin "N22")
    (pin "N23")
    (pin "N28")
    (pin "N31")
    (pin "N5")
    (pin "P11")
    (pin "P12")
    (pin "P13")
    (pin "P14")
    (pin "P15")
    (pin "P16")
    (pin "P17")
    (pin "P18")
    (pin "P19")
    (pin "P20")
    (pin "P21")
    (pin "P22")
    (pin "R11")
    (pin "R12")
    (pin "R13")
    (pin "R14")
    (pin "R15")
    (pin "R16")
    (pin "R17")
    (pin "R18")
    (pin "R19")
    (pin "R2")
    (pin "R20")
    (pin "R21")
    (pin "R22")
    (pin "R28")
    (pin "R31")
    (pin "R5")
    (pin "T11")
    (pin "T12")
    (pin "T13")
    (pin "T14")
    (pin "T15")
    (pin "T16")
    (pin "T17")
    (pin "T18")
    (pin "T19")
    (pin "T20")
    (pin "T21")
    (pin "T22")
    (pin "U11")
    (pin "U12")
    (pin "U13")
    (pin "U14")
    (pin "U15")
    (pin "U16")
    (pin "U17")
    (pin "U18")
    (pin "U19")
    (pin "U20")
    (pin "U21")
    (pin "U22")
    (pin "V11")
    (pin "V12")
    (pin "V13")
    (pin "V14")
    (pin "V15")
    (pin "V16")
    (pin "V17")
    (pin "V18")
    (pin "V19")
    (pin "V2")
    (pin "V20")
    (pin "V21")
    (pin "V22")
    (pin "V28")
    (pin "V3")
    (pin "V30")
    (pin "V31")
    (pin "V5")
    (pin "W11")
    (pin "W12")
    (pin "W13")
    (pin "W14")
    (pin "W15")
    (pin "W16")
    (pin "W17")
    (pin "W18")
    (pin "W19")
    (pin "W20")
    (pin "W21")
    (pin "W22")
    (pin "W27")
    (pin "W6")
    (pin "Y10")
    (pin "Y11")
    (pin "Y12")
    (pin "Y13")
    (pin "Y14")
    (pin "Y15")
    (pin "Y16")
    (pin "Y17")
    (pin "Y18")
    (pin "Y19")
    (pin "Y2")
    (pin "Y20")
    (pin "Y21")
    (pin "Y22")
    (pin "Y23")
    (pin "Y31")
    (pin "A10")
    (pin "A11")
    (pin "A13")
    (pin "A14")
    (pin "A15")
    (pin "A16")
    (pin "A17")
    (pin "A2")
    (pin "A3")
    (pin "A4")
    (pin "A5")
    (pin "A7")
    (pin "A8")
    (pin "A9")
    (pin "B10")
    (pin "B11")
    (pin "B14")
    (pin "B16")
    (pin "B17")
    (pin "B3")
    (pin "B4")
    (pin "B7")
    (pin "B8")
    (pin "C10")
    (pin "C11")
    (pin "C13")
    (pin "C14")
    (pin "C15")
    (pin "C16")
    (pin "C17")
    (pin "C7")
    (pin "C8")
    (pin "C9")
    (pin "D10")
    (pin "D11")
    (pin "D13")
    (pin "D14")
    (pin "D15")
    (pin "D16")
    (pin "D17")
    (pin "D7")
    (pin "D8")
    (pin "D9")
    (pin "E10")
    (pin "E11")
    (pin "E14")
    (pin "E16")
    (pin "E8")
    (pin "F10")
    (pin "F11")
    (pin "F13")
    (pin "F14")
    (pin "F15")
    (pin "F16")
    (pin "F8")
    (pin "F9")
    (pin "K12")
    (pin "K14")
    (pin "K15")
    (pin "K16")
    (pin "A18")
    (pin "A19")
    (pin "A20")
    (pin "A22")
    (pin "A23")
    (pin "A24")
    (pin "A25")
    (pin "A26")
    (pin "A28")
    (pin "A29")
    (pin "A30")
    (pin "A31")
    (pin "B19")
    (pin "B22")
    (pin "B23")
    (pin "B25")
    (pin "B26")
    (pin "B29")
    (pin "B30")
    (pin "C18")
    (pin "C19")
    (pin "C20")
    (pin "C22")
    (pin "C23")
    (pin "C24")
    (pin "C25")
    (pin "C26")
    (pin "D18")
    (pin "D19")
    (pin "D20")
    (pin "D22")
    (pin "D23")
    (pin "D24")
    (pin "D25")
    (pin "D26")
    (pin "E17")
    (pin "E19")
    (pin "E22")
    (pin "E23")
    (pin "E25")
    (pin "F17")
    (pin "F18")
    (pin "F19")
    (pin "F20")
    (pin "F22")
    (pin "F23")
    (pin "F24")
    (pin "F25")
    (pin "K17")
    (pin "K18")
    (pin "K19")
    (pin "K21")
    (pin "B32")
    (pin "C28")
    (pin "C29")
    (pin "C30")
    (pin "C31")
    (pin "C32")
    (pin "D28")
    (pin "D29")
    (pin "D30")
    (pin "D31")
    (pin "D32")
    (pin "E29")
    (pin "E30")
    (pin "E32")
    (pin "F28")
    (pin "F29")
    (pin "F30")
    (pin "F31")
    (pin "F32")
    (pin "H27")
    (pin "H28")
    (pin "H30")
    (pin "H31")
    (pin "H32")
    (pin "J26")
    (pin "J27")
    (pin "J29")
    (pin "J30")
    (pin "J32")
    (pin "K26")
    (pin "K27")
    (pin "K28")
    (pin "K29")
    (pin "K30")
    (pin "K31")
    (pin "K32")
    (pin "L26")
    (pin "L27")
    (pin "L29")
    (pin "L30")
    (pin "L31")
    (pin "L32")
    (pin "M23")
    (pin "N26")
    (pin "N27")
    (pin "N29")
    (pin "N30")
    (pin "P23")
    (pin "P26")
    (pin "P27")
    (pin "R23")
    (pin "T23")
    (pin "AA23")
    (pin "AB26")
    (pin "AB27")
    (pin "AB28")
    (pin "AB29")
    (pin "AB30")
    (pin "AB31")
    (pin "AB32")
    (pin "AC26")
    (pin "AC27")
    (pin "AC28")
    (pin "AC30")
    (pin "AC31")
    (pin "AC32")
    (pin "AD26")
    (pin "AD27")
    (pin "AD29")
    (pin "AD30")
    (pin "AD32")
    (pin "AE27")
    (pin "AE28")
    (pin "AE29")
    (pin "AE30")
    (pin "AE31")
    (pin "AE32")
    (pin "N32")
    (pin "P28")
    (pin "P29")
    (pin "P30")
    (pin "P31")
    (pin "P32")
    (pin "R26")
    (pin "R27")
    (pin "R29")
    (pin "R30")
    (pin "R32")
    (pin "T26")
    (pin "T27")
    (pin "T28")
    (pin "T29")
    (pin "T30")
    (pin "T31")
    (pin "T32")
    (pin "U23")
    (pin "U26")
    (pin "U27")
    (pin "U28")
    (pin "U29")
    (pin "U30")
    (pin "U31")
    (pin "U32")
    (pin "V23")
    (pin "V26")
    (pin "V27")
    (pin "V29")
    (pin "V32")
    (pin "W23")
    (pin "W28")
    (pin "W29")
    (pin "W30")
    (pin "W31")
    (pin "W32")
    (pin "Y26")
    (pin "Y27")
    (pin "Y28")
    (pin "Y29")
    (pin "Y30")
    (pin "Y32")
    (pin "AB23")
    (pin "AC23")
    (pin "AG28")
    (pin "AG29")
    (pin "AG30")
    (pin "AG32")
    (pin "AH28")
    (pin "AH30")
    (pin "AH32")
    (pin "AJ28")
    (pin "AJ29")
    (pin "AJ30")
    (pin "AJ31")
    (pin "AJ32")
    (pin "AK28")
    (pin "AK29")
    (pin "AK30")
    (pin "AK31")
    (pin "AK32")
    (pin "AL28")
    (pin "AL30")
    (pin "AL32")
    (pin "AM28")
    (pin "AM29")
    (pin "AM30")
    (pin "AM31")
    (pin "AA10")
    (pin "AB1")
    (pin "AB2")
    (pin "AB3")
    (pin "AB4")
    (pin "AB5")
    (pin "AB6")
    (pin "AB7")
    (pin "AC1")
    (pin "AC2")
    (pin "AC3")
    (pin "AC5")
    (pin "AC6")
    (pin "AC7")
    (pin "AD1")
    (pin "AD3")
    (pin "AD4")
    (pin "AD6")
    (pin "AD7")
    (pin "AE1")
    (pin "AE2")
    (pin "AE3")
    (pin "AE4")
    (pin "AE5")
    (pin "AE6")
    (pin "N1")
    (pin "P1")
    (pin "P2")
    (pin "P3")
    (pin "P4")
    (pin "P5")
    (pin "R1")
    (pin "R3")
    (pin "R4")
    (pin "R6")
    (pin "R7")
    (pin "T1")
    (pin "T2")
    (pin "T3")
    (pin "T4")
    (pin "T5")
    (pin "T6")
    (pin "T7")
    (pin "U1")
    (pin "U10")
    (pin "U2")
    (pin "U3")
    (pin "U4")
    (pin "U5")
    (pin "U6")
    (pin "U7")
    (pin "V1")
    (pin "V10")
    (pin "V4")
    (pin "V6")
    (pin "V7")
    (pin "W1")
    (pin "W10")
    (pin "W2")
    (pin "W3")
    (pin "W4")
    (pin "W5")
    (pin "Y1")
    (pin "Y3")
    (pin "Y4")
    (pin "Y5")
    (pin "Y6")
    (pin "Y7")
    (pin "B1")
    (pin "C1")
    (pin "C2")
    (pin "C3")
    (pin "C4")
    (pin "C5")
    (pin "D1")
    (pin "D2")
    (pin "D3")
    (pin "D4")
    (pin "D5")
    (pin "E1")
    (pin "E3")
    (pin "E4")
    (pin "F1")
    (pin "F2")
    (pin "F3")
    (pin "F4")
    (pin "F5")
    (pin "H1")
    (pin "H2")
    (pin "H3")
    (pin "H5")
    (pin "H6")
    (pin "J1")
    (pin "J3")
    (pin "J4")
    (pin "J6")
    (pin "J7")
    (pin "K1")
    (pin "K2")
    (pin "K3")
    (pin "K4")
    (pin "K5")
    (pin "K6")
    (pin "K7")
    (pin "L1")
    (pin "L2")
    (pin "L3")
    (pin "L4")
    (pin "L6")
    (pin "L7")
    (pin "M10")
    (pin "N3")
    (pin "N4")
    (pin "N6")
    (pin "N7")
    (pin "P10")
    (pin "P6")
    (pin "P7")
    (pin "R10")
    (pin "T10")
    (pin "AB10")
    (pin "AC10")
    (pin "AG1")
    (pin "AG3")
    (pin "AG4")
    (pin "AH1")
    (pin "AH3")
    (pin "AH4")
    (pin "AJ1")
    (pin "AJ2")
    (pin "AJ3")
    (pin "AJ4")
    (pin "AK1")
    (pin "AK2")
    (pin "AK3")
    (pin "AK4")
    (pin "AL1")
    (pin "AL3")
    (pin "AL4")
    (pin "AM2")
    (pin "AM3")
    (pin "AM4")
    (pin "AG5")
    (pin "AJ5")
    (pin "AK5")
    (pin "AM5")
    (pin "AK10")
    (pin "AK12")
    (pin "AK13")
    (pin "AK9")
    (pin "AM11")
    (pin "AM12")
    (pin "AM14")
    (pin "AM15")
    (pin "AM8")
    (pin "AM9")
    (pin "AK18")
    (pin "AK19")
    (pin "AK21")
    (pin "AK22")
    (pin "AM17")
    (pin "AM18")
    (pin "AM20")
    (pin "AM21")
    (pin "AM23")
    (pin "AM24")
    (instances
      (project "ecp5-dc-scm"
        (path ""
          (reference "U21") (unit 4)
        )
      )
    )
  )

  (symbol (lib_id "antmicroFPGAChips:ECP5_LFE5UM5G-85") (at 238.76 57.15 0) (unit 5)
    (in_bom yes) (on_board yes) (dnp no)
    (property "Reference" "U21" (at 243.84 41.91 0)
      (effects (font (size 1.524 1.524)) (justify left))
    )
    (property "Value" "ECP5UM5G_85_CABGA756" (at 240.03 222.25 0)
      (effects (font (size 1.524 1.524)) (justify left))
    )
    (property "Footprint" "antmicro-footprints:BGA-1024-756_27x27mm_Layout32x32_P0.8mm" (at 238.76 57.15 0)
      (effects (font (size 1.27 1.27)) hide)
    )
    (property "Datasheet" "https://www.latticesemi.com/-/media/LatticeSemi/Documents/DataSheets/ECP5/FPGA-DS-02012-2-2-ECP5-ECP5G-Family-Data-Sheet.ashx?document_id=50461" (at 238.76 57.15 0)
      (effects (font (size 1.27 1.27)) hide)
    )
    (property "MPN" "LFE5UM5G-85F-8BG756C" (at 242.57 58.42 0)
      (effects (font (size 1.524 1.524)) (justify right) hide)
    )
    (property "Manufacturer" "Lattice Semiconductor" (at 267.462 132.0546 0)
      (effects (font (size 1.27 1.27)) (justify left) hide)
    )
    (property "Author" "Antmicro" (at 316.23 76.2 0)
      (effects (font (size 1.27 1.27) (thickness 0.15)) (justify left bottom) hide)
    )
    (property "License" "Apache-2.0" (at 316.23 78.74 0)
      (effects (font (size 1.27 1.27) (thickness 0.15)) (justify left bottom) hide)
    )
    (pin "AA11")
    (pin "AA12")
    (pin "AA13")
    (pin "AA14")
    (pin "AA15")
    (pin "AA16")
    (pin "AA17")
    (pin "AA18")
    (pin "AA19")
    (pin "AA20")
    (pin "AA21")
    (pin "AA22")
    (pin "AB11")
    (pin "AB12")
    (pin "AB13")
    (pin "AB14")
    (pin "AB15")
    (pin "AB16")
    (pin "AB17")
    (pin "AB18")
    (pin "AB19")
    (pin "AB20")
    (pin "AB21")
    (pin "AB22")
    (pin "AC11")
    (pin "AC12")
    (pin "AC13")
    (pin "AC14")
    (pin "AC15")
    (pin "AC16")
    (pin "AC17")
    (pin "AC18")
    (pin "AC19")
    (pin "AC20")
    (pin "AC21")
    (pin "AC22")
    (pin "AC29")
    (pin "AC4")
    (pin "AD2")
    (pin "AD28")
    (pin "AD31")
    (pin "AD5")
    (pin "AE26")
    (pin "AE7")
    (pin "AF11")
    (pin "AF12")
    (pin "AF14")
    (pin "AF15")
    (pin "AF16")
    (pin "AF17")
    (pin "AF19")
    (pin "AF20")
    (pin "AF22")
    (pin "AF23")
    (pin "AG11")
    (pin "AG12")
    (pin "AG14")
    (pin "AG15")
    (pin "AG16")
    (pin "AG17")
    (pin "AG19")
    (pin "AG2")
    (pin "AG20")
    (pin "AG22")
    (pin "AG23")
    (pin "AG24")
    (pin "AG31")
    (pin "AG9")
    (pin "AH11")
    (pin "AH12")
    (pin "AH14")
    (pin "AH15")
    (pin "AH16")
    (pin "AH17")
    (pin "AH19")
    (pin "AH2")
    (pin "AH20")
    (pin "AH22")
    (pin "AH23")
    (pin "AH24")
    (pin "AH25")
    (pin "AH26")
    (pin "AH29")
    (pin "AH31")
    (pin "AH5")
    (pin "AH7")
    (pin "AH8")
    (pin "AH9")
    (pin "AJ10")
    (pin "AJ11")
    (pin "AJ12")
    (pin "AJ13")
    (pin "AJ14")
    (pin "AJ15")
    (pin "AJ16")
    (pin "AJ17")
    (pin "AJ18")
    (pin "AJ19")
    (pin "AJ20")
    (pin "AJ21")
    (pin "AJ22")
    (pin "AJ23")
    (pin "AJ24")
    (pin "AJ25")
    (pin "AJ26")
    (pin "AJ7")
    (pin "AJ8")
    (pin "AJ9")
    (pin "AK11")
    (pin "AK14")
    (pin "AK15")
    (pin "AK16")
    (pin "AK17")
    (pin "AK20")
    (pin "AK23")
    (pin "AK24")
    (pin "AK25")
    (pin "AK26")
    (pin "AK7")
    (pin "AK8")
    (pin "AL11")
    (pin "AL12")
    (pin "AL14")
    (pin "AL15")
    (pin "AL17")
    (pin "AL18")
    (pin "AL2")
    (pin "AL20")
    (pin "AL21")
    (pin "AL23")
    (pin "AL24")
    (pin "AL26")
    (pin "AL29")
    (pin "AL31")
    (pin "AL5")
    (pin "AL7")
    (pin "AL8")
    (pin "AL9")
    (pin "AM26")
    (pin "AM7")
    (pin "B13")
    (pin "B15")
    (pin "B18")
    (pin "B2")
    (pin "B20")
    (pin "B24")
    (pin "B28")
    (pin "B31")
    (pin "B5")
    (pin "B9")
    (pin "E13")
    (pin "E15")
    (pin "E18")
    (pin "E2")
    (pin "E20")
    (pin "E24")
    (pin "E26")
    (pin "E28")
    (pin "E31")
    (pin "E5")
    (pin "E7")
    (pin "E9")
    (pin "G10")
    (pin "G11")
    (pin "G14")
    (pin "G15")
    (pin "G16")
    (pin "G17")
    (pin "G18")
    (pin "G19")
    (pin "G22")
    (pin "G23")
    (pin "G24")
    (pin "G9")
    (pin "H29")
    (pin "H4")
    (pin "J2")
    (pin "J28")
    (pin "J31")
    (pin "J5")
    (pin "K10")
    (pin "K11")
    (pin "K13")
    (pin "K20")
    (pin "K22")
    (pin "K23")
    (pin "L10")
    (pin "L11")
    (pin "L12")
    (pin "L13")
    (pin "L14")
    (pin "L15")
    (pin "L16")
    (pin "L17")
    (pin "L18")
    (pin "L19")
    (pin "L20")
    (pin "L21")
    (pin "L22")
    (pin "L23")
    (pin "L28")
    (pin "L5")
    (pin "M11")
    (pin "M12")
    (pin "M13")
    (pin "M14")
    (pin "M15")
    (pin "M16")
    (pin "M17")
    (pin "M18")
    (pin "M19")
    (pin "M20")
    (pin "M21")
    (pin "M22")
    (pin "N10")
    (pin "N11")
    (pin "N12")
    (pin "N13")
    (pin "N14")
    (pin "N15")
    (pin "N16")
    (pin "N17")
    (pin "N18")
    (pin "N19")
    (pin "N2")
    (pin "N20")
    (pin "N21")
    (pin "N22")
    (pin "N23")
    (pin "N28")
    (pin "N31")
    (pin "N5")
    (pin "P11")
    (pin "P12")
    (pin "P13")
    (pin "P14")
    (pin "P15")
    (pin "P16")
    (pin "P17")
    (pin "P18")
    (pin "P19")
    (pin "P20")
    (pin "P21")
    (pin "P22")
    (pin "R11")
    (pin "R12")
    (pin "R13")
    (pin "R14")
    (pin "R15")
    (pin "R16")
    (pin "R17")
    (pin "R18")
    (pin "R19")
    (pin "R2")
    (pin "R20")
    (pin "R21")
    (pin "R22")
    (pin "R28")
    (pin "R31")
    (pin "R5")
    (pin "T11")
    (pin "T12")
    (pin "T13")
    (pin "T14")
    (pin "T15")
    (pin "T16")
    (pin "T17")
    (pin "T18")
    (pin "T19")
    (pin "T20")
    (pin "T21")
    (pin "T22")
    (pin "U11")
    (pin "U12")
    (pin "U13")
    (pin "U14")
    (pin "U15")
    (pin "U16")
    (pin "U17")
    (pin "U18")
    (pin "U19")
    (pin "U20")
    (pin "U21")
    (pin "U22")
    (pin "V11")
    (pin "V12")
    (pin "V13")
    (pin "V14")
    (pin "V15")
    (pin "V16")
    (pin "V17")
    (pin "V18")
    (pin "V19")
    (pin "V2")
    (pin "V20")
    (pin "V21")
    (pin "V22")
    (pin "V28")
    (pin "V3")
    (pin "V30")
    (pin "V31")
    (pin "V5")
    (pin "W11")
    (pin "W12")
    (pin "W13")
    (pin "W14")
    (pin "W15")
    (pin "W16")
    (pin "W17")
    (pin "W18")
    (pin "W19")
    (pin "W20")
    (pin "W21")
    (pin "W22")
    (pin "W27")
    (pin "W6")
    (pin "Y10")
    (pin "Y11")
    (pin "Y12")
    (pin "Y13")
    (pin "Y14")
    (pin "Y15")
    (pin "Y16")
    (pin "Y17")
    (pin "Y18")
    (pin "Y19")
    (pin "Y2")
    (pin "Y20")
    (pin "Y21")
    (pin "Y22")
    (pin "Y23")
    (pin "Y31")
    (pin "A10")
    (pin "A11")
    (pin "A13")
    (pin "A14")
    (pin "A15")
    (pin "A16")
    (pin "A17")
    (pin "A2")
    (pin "A3")
    (pin "A4")
    (pin "A5")
    (pin "A7")
    (pin "A8")
    (pin "A9")
    (pin "B10")
    (pin "B11")
    (pin "B14")
    (pin "B16")
    (pin "B17")
    (pin "B3")
    (pin "B4")
    (pin "B7")
    (pin "B8")
    (pin "C10")
    (pin "C11")
    (pin "C13")
    (pin "C14")
    (pin "C15")
    (pin "C16")
    (pin "C17")
    (pin "C7")
    (pin "C8")
    (pin "C9")
    (pin "D10")
    (pin "D11")
    (pin "D13")
    (pin "D14")
    (pin "D15")
    (pin "D16")
    (pin "D17")
    (pin "D7")
    (pin "D8")
    (pin "D9")
    (pin "E10")
    (pin "E11")
    (pin "E14")
    (pin "E16")
    (pin "E8")
    (pin "F10")
    (pin "F11")
    (pin "F13")
    (pin "F14")
    (pin "F15")
    (pin "F16")
    (pin "F8")
    (pin "F9")
    (pin "K12")
    (pin "K14")
    (pin "K15")
    (pin "K16")
    (pin "A18")
    (pin "A19")
    (pin "A20")
    (pin "A22")
    (pin "A23")
    (pin "A24")
    (pin "A25")
    (pin "A26")
    (pin "A28")
    (pin "A29")
    (pin "A30")
    (pin "A31")
    (pin "B19")
    (pin "B22")
    (pin "B23")
    (pin "B25")
    (pin "B26")
    (pin "B29")
    (pin "B30")
    (pin "C18")
    (pin "C19")
    (pin "C20")
    (pin "C22")
    (pin "C23")
    (pin "C24")
    (pin "C25")
    (pin "C26")
    (pin "D18")
    (pin "D19")
    (pin "D20")
    (pin "D22")
    (pin "D23")
    (pin "D24")
    (pin "D25")
    (pin "D26")
    (pin "E17")
    (pin "E19")
    (pin "E22")
    (pin "E23")
    (pin "E25")
    (pin "F17")
    (pin "F18")
    (pin "F19")
    (pin "F20")
    (pin "F22")
    (pin "F23")
    (pin "F24")
    (pin "F25")
    (pin "K17")
    (pin "K18")
    (pin "K19")
    (pin "K21")
    (pin "B32")
    (pin "C28")
    (pin "C29")
    (pin "C30")
    (pin "C31")
    (pin "C32")
    (pin "D28")
    (pin "D29")
    (pin "D30")
    (pin "D31")
    (pin "D32")
    (pin "E29")
    (pin "E30")
    (pin "E32")
    (pin "F28")
    (pin "F29")
    (pin "F30")
    (pin "F31")
    (pin "F32")
    (pin "H27")
    (pin "H28")
    (pin "H30")
    (pin "H31")
    (pin "H32")
    (pin "J26")
    (pin "J27")
    (pin "J29")
    (pin "J30")
    (pin "J32")
    (pin "K26")
    (pin "K27")
    (pin "K28")
    (pin "K29")
    (pin "K30")
    (pin "K31")
    (pin "K32")
    (pin "L26")
    (pin "L27")
    (pin "L29")
    (pin "L30")
    (pin "L31")
    (pin "L32")
    (pin "M23")
    (pin "N26")
    (pin "N27")
    (pin "N29")
    (pin "N30")
    (pin "P23")
    (pin "P26")
    (pin "P27")
    (pin "R23")
    (pin "T23")
    (pin "AA23")
    (pin "AB26")
    (pin "AB27")
    (pin "AB28")
    (pin "AB29")
    (pin "AB30")
    (pin "AB31")
    (pin "AB32")
    (pin "AC26")
    (pin "AC27")
    (pin "AC28")
    (pin "AC30")
    (pin "AC31")
    (pin "AC32")
    (pin "AD26")
    (pin "AD27")
    (pin "AD29")
    (pin "AD30")
    (pin "AD32")
    (pin "AE27")
    (pin "AE28")
    (pin "AE29")
    (pin "AE30")
    (pin "AE31")
    (pin "AE32")
    (pin "N32")
    (pin "P28")
    (pin "P29")
    (pin "P30")
    (pin "P31")
    (pin "P32")
    (pin "R26")
    (pin "R27")
    (pin "R29")
    (pin "R30")
    (pin "R32")
    (pin "T26")
    (pin "T27")
    (pin "T28")
    (pin "T29")
    (pin "T30")
    (pin "T31")
    (pin "T32")
    (pin "U23")
    (pin "U26")
    (pin "U27")
    (pin "U28")
    (pin "U29")
    (pin "U30")
    (pin "U31")
    (pin "U32")
    (pin "V23")
    (pin "V26")
    (pin "V27")
    (pin "V29")
    (pin "V32")
    (pin "W23")
    (pin "W28")
    (pin "W29")
    (pin "W30")
    (pin "W31")
    (pin "W32")
    (pin "Y26")
    (pin "Y27")
    (pin "Y28")
    (pin "Y29")
    (pin "Y30")
    (pin "Y32")
    (pin "AB23")
    (pin "AC23")
    (pin "AG28")
    (pin "AG29")
    (pin "AG30")
    (pin "AG32")
    (pin "AH28")
    (pin "AH30")
    (pin "AH32")
    (pin "AJ28")
    (pin "AJ29")
    (pin "AJ30")
    (pin "AJ31")
    (pin "AJ32")
    (pin "AK28")
    (pin "AK29")
    (pin "AK30")
    (pin "AK31")
    (pin "AK32")
    (pin "AL28")
    (pin "AL30")
    (pin "AL32")
    (pin "AM28")
    (pin "AM29")
    (pin "AM30")
    (pin "AM31")
    (pin "AA10")
    (pin "AB1")
    (pin "AB2")
    (pin "AB3")
    (pin "AB4")
    (pin "AB5")
    (pin "AB6")
    (pin "AB7")
    (pin "AC1")
    (pin "AC2")
    (pin "AC3")
    (pin "AC5")
    (pin "AC6")
    (pin "AC7")
    (pin "AD1")
    (pin "AD3")
    (pin "AD4")
    (pin "AD6")
    (pin "AD7")
    (pin "AE1")
    (pin "AE2")
    (pin "AE3")
    (pin "AE4")
    (pin "AE5")
    (pin "AE6")
    (pin "N1")
    (pin "P1")
    (pin "P2")
    (pin "P3")
    (pin "P4")
    (pin "P5")
    (pin "R1")
    (pin "R3")
    (pin "R4")
    (pin "R6")
    (pin "R7")
    (pin "T1")
    (pin "T2")
    (pin "T3")
    (pin "T4")
    (pin "T5")
    (pin "T6")
    (pin "T7")
    (pin "U1")
    (pin "U10")
    (pin "U2")
    (pin "U3")
    (pin "U4")
    (pin "U5")
    (pin "U6")
    (pin "U7")
    (pin "V1")
    (pin "V10")
    (pin "V4")
    (pin "V6")
    (pin "V7")
    (pin "W1")
    (pin "W10")
    (pin "W2")
    (pin "W3")
    (pin "W4")
    (pin "W5")
    (pin "Y1")
    (pin "Y3")
    (pin "Y4")
    (pin "Y5")
    (pin "Y6")
    (pin "Y7")
    (pin "B1")
    (pin "C1")
    (pin "C2")
    (pin "C3")
    (pin "C4")
    (pin "C5")
    (pin "D1")
    (pin "D2")
    (pin "D3")
    (pin "D4")
    (pin "D5")
    (pin "E1")
    (pin "E3")
    (pin "E4")
    (pin "F1")
    (pin "F2")
    (pin "F3")
    (pin "F4")
    (pin "F5")
    (pin "H1")
    (pin "H2")
    (pin "H3")
    (pin "H5")
    (pin "H6")
    (pin "J1")
    (pin "J3")
    (pin "J4")
    (pin "J6")
    (pin "J7")
    (pin "K1")
    (pin "K2")
    (pin "K3")
    (pin "K4")
    (pin "K5")
    (pin "K6")
    (pin "K7")
    (pin "L1")
    (pin "L2")
    (pin "L3")
    (pin "L4")
    (pin "L6")
    (pin "L7")
    (pin "M10")
    (pin "N3")
    (pin "N4")
    (pin "N6")
    (pin "N7")
    (pin "P10")
    (pin "P6")
    (pin "P7")
    (pin "R10")
    (pin "T10")
    (pin "AB10")
    (pin "AC10")
    (pin "AG1")
    (pin "AG3")
    (pin "AG4")
    (pin "AH1")
    (pin "AH3")
    (pin "AH4")
    (pin "AJ1")
    (pin "AJ2")
    (pin "AJ3")
    (pin "AJ4")
    (pin "AK1")
    (pin "AK2")
    (pin "AK3")
    (pin "AK4")
    (pin "AL1")
    (pin "AL3")
    (pin "AL4")
    (pin "AM2")
    (pin "AM3")
    (pin "AM4")
    (pin "AG5")
    (pin "AJ5")
    (pin "AK5")
    (pin "AM5")
    (pin "AK10")
    (pin "AK12")
    (pin "AK13")
    (pin "AK9")
    (pin "AM11")
    (pin "AM12")
    (pin "AM14")
    (pin "AM15")
    (pin "AM8")
    (pin "AM9")
    (pin "AK18")
    (pin "AK19")
    (pin "AK21")
    (pin "AK22")
    (pin "AM17")
    (pin "AM18")
    (pin "AM20")
    (pin "AM21")
    (pin "AM23")
    (pin "AM24")
    (instances
      (project "ecp5-dc-scm"
        (path ""
          (reference "U21") (unit 5)
        )
      )
    )
  )

  (symbol (lib_id "antmicroFPGAChips:ECP5_LFE5UM5G-85") (at 48.26 57.15 0) (unit 2)
    (in_bom yes) (on_board yes) (dnp no) (fields_autoplaced)
    (property "Reference" "U21" (at 62.23 49.53 0)
      (effects (font (size 1.524 1.524)))
    )
    (property "Value" "ECP5UM5G_85_CABGA756" (at 62.23 52.07 0)
      (effects (font (size 1.524 1.524)))
    )
    (property "Footprint" "antmicro-footprints:BGA-1024-756_27x27mm_Layout32x32_P0.8mm" (at 48.26 57.15 0)
      (effects (font (size 1.27 1.27)) hide)
    )
    (property "Datasheet" "https://www.latticesemi.com/-/media/LatticeSemi/Documents/DataSheets/ECP5/FPGA-DS-02012-2-2-ECP5-ECP5G-Family-Data-Sheet.ashx?document_id=50461" (at 48.26 57.15 0)
      (effects (font (size 1.27 1.27)) hide)
    )
    (property "MPN" "LFE5UM5G-85F-8BG756C" (at 52.07 58.42 0)
      (effects (font (size 1.524 1.524)) (justify right) hide)
    )
    (property "Manufacturer" "Lattice Semiconductor" (at 76.962 121.8946 0)
      (effects (font (size 1.27 1.27)) (justify left) hide)
    )
    (property "Author" "Antmicro" (at 125.73 76.2 0)
      (effects (font (size 1.27 1.27) (thickness 0.15)) (justify left bottom) hide)
    )
    (property "License" "Apache-2.0" (at 125.73 78.74 0)
      (effects (font (size 1.27 1.27) (thickness 0.15)) (justify left bottom) hide)
    )
    (pin "AA11")
    (pin "AA12")
    (pin "AA13")
    (pin "AA14")
    (pin "AA15")
    (pin "AA16")
    (pin "AA17")
    (pin "AA18")
    (pin "AA19")
    (pin "AA20")
    (pin "AA21")
    (pin "AA22")
    (pin "AB11")
    (pin "AB12")
    (pin "AB13")
    (pin "AB14")
    (pin "AB15")
    (pin "AB16")
    (pin "AB17")
    (pin "AB18")
    (pin "AB19")
    (pin "AB20")
    (pin "AB21")
    (pin "AB22")
    (pin "AC11")
    (pin "AC12")
    (pin "AC13")
    (pin "AC14")
    (pin "AC15")
    (pin "AC16")
    (pin "AC17")
    (pin "AC18")
    (pin "AC19")
    (pin "AC20")
    (pin "AC21")
    (pin "AC22")
    (pin "AC29")
    (pin "AC4")
    (pin "AD2")
    (pin "AD28")
    (pin "AD31")
    (pin "AD5")
    (pin "AE26")
    (pin "AE7")
    (pin "AF11")
    (pin "AF12")
    (pin "AF14")
    (pin "AF15")
    (pin "AF16")
    (pin "AF17")
    (pin "AF19")
    (pin "AF20")
    (pin "AF22")
    (pin "AF23")
    (pin "AG11")
    (pin "AG12")
    (pin "AG14")
    (pin "AG15")
    (pin "AG16")
    (pin "AG17")
    (pin "AG19")
    (pin "AG2")
    (pin "AG20")
    (pin "AG22")
    (pin "AG23")
    (pin "AG24")
    (pin "AG31")
    (pin "AG9")
    (pin "AH11")
    (pin "AH12")
    (pin "AH14")
    (pin "AH15")
    (pin "AH16")
    (pin "AH17")
    (pin "AH19")
    (pin "AH2")
    (pin "AH20")
    (pin "AH22")
    (pin "AH23")
    (pin "AH24")
    (pin "AH25")
    (pin "AH26")
    (pin "AH29")
    (pin "AH31")
    (pin "AH5")
    (pin "AH7")
    (pin "AH8")
    (pin "AH9")
    (pin "AJ10")
    (pin "AJ11")
    (pin "AJ12")
    (pin "AJ13")
    (pin "AJ14")
    (pin "AJ15")
    (pin "AJ16")
    (pin "AJ17")
    (pin "AJ18")
    (pin "AJ19")
    (pin "AJ20")
    (pin "AJ21")
    (pin "AJ22")
    (pin "AJ23")
    (pin "AJ24")
    (pin "AJ25")
    (pin "AJ26")
    (pin "AJ7")
    (pin "AJ8")
    (pin "AJ9")
    (pin "AK11")
    (pin "AK14")
    (pin "AK15")
    (pin "AK16")
    (pin "AK17")
    (pin "AK20")
    (pin "AK23")
    (pin "AK24")
    (pin "AK25")
    (pin "AK26")
    (pin "AK7")
    (pin "AK8")
    (pin "AL11")
    (pin "AL12")
    (pin "AL14")
    (pin "AL15")
    (pin "AL17")
    (pin "AL18")
    (pin "AL2")
    (pin "AL20")
    (pin "AL21")
    (pin "AL23")
    (pin "AL24")
    (pin "AL26")
    (pin "AL29")
    (pin "AL31")
    (pin "AL5")
    (pin "AL7")
    (pin "AL8")
    (pin "AL9")
    (pin "AM26")
    (pin "AM7")
    (pin "B13")
    (pin "B15")
    (pin "B18")
    (pin "B2")
    (pin "B20")
    (pin "B24")
    (pin "B28")
    (pin "B31")
    (pin "B5")
    (pin "B9")
    (pin "E13")
    (pin "E15")
    (pin "E18")
    (pin "E2")
    (pin "E20")
    (pin "E24")
    (pin "E26")
    (pin "E28")
    (pin "E31")
    (pin "E5")
    (pin "E7")
    (pin "E9")
    (pin "G10")
    (pin "G11")
    (pin "G14")
    (pin "G15")
    (pin "G16")
    (pin "G17")
    (pin "G18")
    (pin "G19")
    (pin "G22")
    (pin "G23")
    (pin "G24")
    (pin "G9")
    (pin "H29")
    (pin "H4")
    (pin "J2")
    (pin "J28")
    (pin "J31")
    (pin "J5")
    (pin "K10")
    (pin "K11")
    (pin "K13")
    (pin "K20")
    (pin "K22")
    (pin "K23")
    (pin "L10")
    (pin "L11")
    (pin "L12")
    (pin "L13")
    (pin "L14")
    (pin "L15")
    (pin "L16")
    (pin "L17")
    (pin "L18")
    (pin "L19")
    (pin "L20")
    (pin "L21")
    (pin "L22")
    (pin "L23")
    (pin "L28")
    (pin "L5")
    (pin "M11")
    (pin "M12")
    (pin "M13")
    (pin "M14")
    (pin "M15")
    (pin "M16")
    (pin "M17")
    (pin "M18")
    (pin "M19")
    (pin "M20")
    (pin "M21")
    (pin "M22")
    (pin "N10")
    (pin "N11")
    (pin "N12")
    (pin "N13")
    (pin "N14")
    (pin "N15")
    (pin "N16")
    (pin "N17")
    (pin "N18")
    (pin "N19")
    (pin "N2")
    (pin "N20")
    (pin "N21")
    (pin "N22")
    (pin "N23")
    (pin "N28")
    (pin "N31")
    (pin "N5")
    (pin "P11")
    (pin "P12")
    (pin "P13")
    (pin "P14")
    (pin "P15")
    (pin "P16")
    (pin "P17")
    (pin "P18")
    (pin "P19")
    (pin "P20")
    (pin "P21")
    (pin "P22")
    (pin "R11")
    (pin "R12")
    (pin "R13")
    (pin "R14")
    (pin "R15")
    (pin "R16")
    (pin "R17")
    (pin "R18")
    (pin "R19")
    (pin "R2")
    (pin "R20")
    (pin "R21")
    (pin "R22")
    (pin "R28")
    (pin "R31")
    (pin "R5")
    (pin "T11")
    (pin "T12")
    (pin "T13")
    (pin "T14")
    (pin "T15")
    (pin "T16")
    (pin "T17")
    (pin "T18")
    (pin "T19")
    (pin "T20")
    (pin "T21")
    (pin "T22")
    (pin "U11")
    (pin "U12")
    (pin "U13")
    (pin "U14")
    (pin "U15")
    (pin "U16")
    (pin "U17")
    (pin "U18")
    (pin "U19")
    (pin "U20")
    (pin "U21")
    (pin "U22")
    (pin "V11")
    (pin "V12")
    (pin "V13")
    (pin "V14")
    (pin "V15")
    (pin "V16")
    (pin "V17")
    (pin "V18")
    (pin "V19")
    (pin "V2")
    (pin "V20")
    (pin "V21")
    (pin "V22")
    (pin "V28")
    (pin "V3")
    (pin "V30")
    (pin "V31")
    (pin "V5")
    (pin "W11")
    (pin "W12")
    (pin "W13")
    (pin "W14")
    (pin "W15")
    (pin "W16")
    (pin "W17")
    (pin "W18")
    (pin "W19")
    (pin "W20")
    (pin "W21")
    (pin "W22")
    (pin "W27")
    (pin "W6")
    (pin "Y10")
    (pin "Y11")
    (pin "Y12")
    (pin "Y13")
    (pin "Y14")
    (pin "Y15")
    (pin "Y16")
    (pin "Y17")
    (pin "Y18")
    (pin "Y19")
    (pin "Y2")
    (pin "Y20")
    (pin "Y21")
    (pin "Y22")
    (pin "Y23")
    (pin "Y31")
    (pin "A10")
    (pin "A11")
    (pin "A13")
    (pin "A14")
    (pin "A15")
    (pin "A16")
    (pin "A17")
    (pin "A2")
    (pin "A3")
    (pin "A4")
    (pin "A5")
    (pin "A7")
    (pin "A8")
    (pin "A9")
    (pin "B10")
    (pin "B11")
    (pin "B14")
    (pin "B16")
    (pin "B17")
    (pin "B3")
    (pin "B4")
    (pin "B7")
    (pin "B8")
    (pin "C10")
    (pin "C11")
    (pin "C13")
    (pin "C14")
    (pin "C15")
    (pin "C16")
    (pin "C17")
    (pin "C7")
    (pin "C8")
    (pin "C9")
    (pin "D10")
    (pin "D11")
    (pin "D13")
    (pin "D14")
    (pin "D15")
    (pin "D16")
    (pin "D17")
    (pin "D7")
    (pin "D8")
    (pin "D9")
    (pin "E10")
    (pin "E11")
    (pin "E14")
    (pin "E16")
    (pin "E8")
    (pin "F10")
    (pin "F11")
    (pin "F13")
    (pin "F14")
    (pin "F15")
    (pin "F16")
    (pin "F8")
    (pin "F9")
    (pin "K12")
    (pin "K14")
    (pin "K15")
    (pin "K16")
    (pin "A18")
    (pin "A19")
    (pin "A20")
    (pin "A22")
    (pin "A23")
    (pin "A24")
    (pin "A25")
    (pin "A26")
    (pin "A28")
    (pin "A29")
    (pin "A30")
    (pin "A31")
    (pin "B19")
    (pin "B22")
    (pin "B23")
    (pin "B25")
    (pin "B26")
    (pin "B29")
    (pin "B30")
    (pin "C18")
    (pin "C19")
    (pin "C20")
    (pin "C22")
    (pin "C23")
    (pin "C24")
    (pin "C25")
    (pin "C26")
    (pin "D18")
    (pin "D19")
    (pin "D20")
    (pin "D22")
    (pin "D23")
    (pin "D24")
    (pin "D25")
    (pin "D26")
    (pin "E17")
    (pin "E19")
    (pin "E22")
    (pin "E23")
    (pin "E25")
    (pin "F17")
    (pin "F18")
    (pin "F19")
    (pin "F20")
    (pin "F22")
    (pin "F23")
    (pin "F24")
    (pin "F25")
    (pin "K17")
    (pin "K18")
    (pin "K19")
    (pin "K21")
    (pin "B32")
    (pin "C28")
    (pin "C29")
    (pin "C30")
    (pin "C31")
    (pin "C32")
    (pin "D28")
    (pin "D29")
    (pin "D30")
    (pin "D31")
    (pin "D32")
    (pin "E29")
    (pin "E30")
    (pin "E32")
    (pin "F28")
    (pin "F29")
    (pin "F30")
    (pin "F31")
    (pin "F32")
    (pin "H27")
    (pin "H28")
    (pin "H30")
    (pin "H31")
    (pin "H32")
    (pin "J26")
    (pin "J27")
    (pin "J29")
    (pin "J30")
    (pin "J32")
    (pin "K26")
    (pin "K27")
    (pin "K28")
    (pin "K29")
    (pin "K30")
    (pin "K31")
    (pin "K32")
    (pin "L26")
    (pin "L27")
    (pin "L29")
    (pin "L30")
    (pin "L31")
    (pin "L32")
    (pin "M23")
    (pin "N26")
    (pin "N27")
    (pin "N29")
    (pin "N30")
    (pin "P23")
    (pin "P26")
    (pin "P27")
    (pin "R23")
    (pin "T23")
    (pin "AA23")
    (pin "AB26")
    (pin "AB27")
    (pin "AB28")
    (pin "AB29")
    (pin "AB30")
    (pin "AB31")
    (pin "AB32")
    (pin "AC26")
    (pin "AC27")
    (pin "AC28")
    (pin "AC30")
    (pin "AC31")
    (pin "AC32")
    (pin "AD26")
    (pin "AD27")
    (pin "AD29")
    (pin "AD30")
    (pin "AD32")
    (pin "AE27")
    (pin "AE28")
    (pin "AE29")
    (pin "AE30")
    (pin "AE31")
    (pin "AE32")
    (pin "N32")
    (pin "P28")
    (pin "P29")
    (pin "P30")
    (pin "P31")
    (pin "P32")
    (pin "R26")
    (pin "R27")
    (pin "R29")
    (pin "R30")
    (pin "R32")
    (pin "T26")
    (pin "T27")
    (pin "T28")
    (pin "T29")
    (pin "T30")
    (pin "T31")
    (pin "T32")
    (pin "U23")
    (pin "U26")
    (pin "U27")
    (pin "U28")
    (pin "U29")
    (pin "U30")
    (pin "U31")
    (pin "U32")
    (pin "V23")
    (pin "V26")
    (pin "V27")
    (pin "V29")
    (pin "V32")
    (pin "W23")
    (pin "W28")
    (pin "W29")
    (pin "W30")
    (pin "W31")
    (pin "W32")
    (pin "Y26")
    (pin "Y27")
    (pin "Y28")
    (pin "Y29")
    (pin "Y30")
    (pin "Y32")
    (pin "AB23")
    (pin "AC23")
    (pin "AG28")
    (pin "AG29")
    (pin "AG30")
    (pin "AG32")
    (pin "AH28")
    (pin "AH30")
    (pin "AH32")
    (pin "AJ28")
    (pin "AJ29")
    (pin "AJ30")
    (pin "AJ31")
    (pin "AJ32")
    (pin "AK28")
    (pin "AK29")
    (pin "AK30")
    (pin "AK31")
    (pin "AK32")
    (pin "AL28")
    (pin "AL30")
    (pin "AL32")
    (pin "AM28")
    (pin "AM29")
    (pin "AM30")
    (pin "AM31")
    (pin "AA10")
    (pin "AB1")
    (pin "AB2")
    (pin "AB3")
    (pin "AB4")
    (pin "AB5")
    (pin "AB6")
    (pin "AB7")
    (pin "AC1")
    (pin "AC2")
    (pin "AC3")
    (pin "AC5")
    (pin "AC6")
    (pin "AC7")
    (pin "AD1")
    (pin "AD3")
    (pin "AD4")
    (pin "AD6")
    (pin "AD7")
    (pin "AE1")
    (pin "AE2")
    (pin "AE3")
    (pin "AE4")
    (pin "AE5")
    (pin "AE6")
    (pin "N1")
    (pin "P1")
    (pin "P2")
    (pin "P3")
    (pin "P4")
    (pin "P5")
    (pin "R1")
    (pin "R3")
    (pin "R4")
    (pin "R6")
    (pin "R7")
    (pin "T1")
    (pin "T2")
    (pin "T3")
    (pin "T4")
    (pin "T5")
    (pin "T6")
    (pin "T7")
    (pin "U1")
    (pin "U10")
    (pin "U2")
    (pin "U3")
    (pin "U4")
    (pin "U5")
    (pin "U6")
    (pin "U7")
    (pin "V1")
    (pin "V10")
    (pin "V4")
    (pin "V6")
    (pin "V7")
    (pin "W1")
    (pin "W10")
    (pin "W2")
    (pin "W3")
    (pin "W4")
    (pin "W5")
    (pin "Y1")
    (pin "Y3")
    (pin "Y4")
    (pin "Y5")
    (pin "Y6")
    (pin "Y7")
    (pin "B1")
    (pin "C1")
    (pin "C2")
    (pin "C3")
    (pin "C4")
    (pin "C5")
    (pin "D1")
    (pin "D2")
    (pin "D3")
    (pin "D4")
    (pin "D5")
    (pin "E1")
    (pin "E3")
    (pin "E4")
    (pin "F1")
    (pin "F2")
    (pin "F3")
    (pin "F4")
    (pin "F5")
    (pin "H1")
    (pin "H2")
    (pin "H3")
    (pin "H5")
    (pin "H6")
    (pin "J1")
    (pin "J3")
    (pin "J4")
    (pin "J6")
    (pin "J7")
    (pin "K1")
    (pin "K2")
    (pin "K3")
    (pin "K4")
    (pin "K5")
    (pin "K6")
    (pin "K7")
    (pin "L1")
    (pin "L2")
    (pin "L3")
    (pin "L4")
    (pin "L6")
    (pin "L7")
    (pin "M10")
    (pin "N3")
    (pin "N4")
    (pin "N6")
    (pin "N7")
    (pin "P10")
    (pin "P6")
    (pin "P7")
    (pin "R10")
    (pin "T10")
    (pin "AB10")
    (pin "AC10")
    (pin "AG1")
    (pin "AG3")
    (pin "AG4")
    (pin "AH1")
    (pin "AH3")
    (pin "AH4")
    (pin "AJ1")
    (pin "AJ2")
    (pin "AJ3")
    (pin "AJ4")
    (pin "AK1")
    (pin "AK2")
    (pin "AK3")
    (pin "AK4")
    (pin "AL1")
    (pin "AL3")
    (pin "AL4")
    (pin "AM2")
    (pin "AM3")
    (pin "AM4")
    (pin "AG5")
    (pin "AJ5")
    (pin "AK5")
    (pin "AM5")
    (pin "AK10")
    (pin "AK12")
    (pin "AK13")
    (pin "AK9")
    (pin "AM11")
    (pin "AM12")
    (pin "AM14")
    (pin "AM15")
    (pin "AM8")
    (pin "AM9")
    (pin "AK18")
    (pin "AK19")
    (pin "AK21")
    (pin "AK22")
    (pin "AM17")
    (pin "AM18")
    (pin "AM20")
    (pin "AM21")
    (pin "AM23")
    (pin "AM24")
    (instances
      (project "ecp5-dc-scm"
        (path ""
          (reference "U21") (unit 2)
        )
      )
    )
  )

  (symbol (lib_id "antmicroFPGAChips:ECP5_LFE5UM5G-85") (at 111.76 57.15 0) (unit 3)
    (in_bom yes) (on_board yes) (dnp no) (fields_autoplaced)
    (property "Reference" "U21" (at 125.73 49.53 0)
      (effects (font (size 1.524 1.524)))
    )
    (property "Value" "ECP5UM5G_85_CABGA756" (at 125.73 52.07 0)
      (effects (font (size 1.524 1.524)))
    )
    (property "Footprint" "antmicro-footprints:BGA-1024-756_27x27mm_Layout32x32_P0.8mm" (at 111.76 57.15 0)
      (effects (font (size 1.27 1.27)) hide)
    )
    (property "Datasheet" "https://www.latticesemi.com/-/media/LatticeSemi/Documents/DataSheets/ECP5/FPGA-DS-02012-2-2-ECP5-ECP5G-Family-Data-Sheet.ashx?document_id=50461" (at 111.76 57.15 0)
      (effects (font (size 1.27 1.27)) hide)
    )
    (property "MPN" "LFE5UM5G-85F-8BG756C" (at 115.57 58.42 0)
      (effects (font (size 1.524 1.524)) (justify right) hide)
    )
    (property "Manufacturer" "Lattice Semiconductor" (at 140.462 111.7346 0)
      (effects (font (size 1.27 1.27)) (justify left) hide)
    )
    (property "Author" "Antmicro" (at 189.23 76.2 0)
      (effects (font (size 1.27 1.27) (thickness 0.15)) (justify left bottom) hide)
    )
    (property "License" "Apache-2.0" (at 189.23 78.74 0)
      (effects (font (size 1.27 1.27) (thickness 0.15)) (justify left bottom) hide)
    )
    (pin "AA11")
    (pin "AA12")
    (pin "AA13")
    (pin "AA14")
    (pin "AA15")
    (pin "AA16")
    (pin "AA17")
    (pin "AA18")
    (pin "AA19")
    (pin "AA20")
    (pin "AA21")
    (pin "AA22")
    (pin "AB11")
    (pin "AB12")
    (pin "AB13")
    (pin "AB14")
    (pin "AB15")
    (pin "AB16")
    (pin "AB17")
    (pin "AB18")
    (pin "AB19")
    (pin "AB20")
    (pin "AB21")
    (pin "AB22")
    (pin "AC11")
    (pin "AC12")
    (pin "AC13")
    (pin "AC14")
    (pin "AC15")
    (pin "AC16")
    (pin "AC17")
    (pin "AC18")
    (pin "AC19")
    (pin "AC20")
    (pin "AC21")
    (pin "AC22")
    (pin "AC29")
    (pin "AC4")
    (pin "AD2")
    (pin "AD28")
    (pin "AD31")
    (pin "AD5")
    (pin "AE26")
    (pin "AE7")
    (pin "AF11")
    (pin "AF12")
    (pin "AF14")
    (pin "AF15")
    (pin "AF16")
    (pin "AF17")
    (pin "AF19")
    (pin "AF20")
    (pin "AF22")
    (pin "AF23")
    (pin "AG11")
    (pin "AG12")
    (pin "AG14")
    (pin "AG15")
    (pin "AG16")
    (pin "AG17")
    (pin "AG19")
    (pin "AG2")
    (pin "AG20")
    (pin "AG22")
    (pin "AG23")
    (pin "AG24")
    (pin "AG31")
    (pin "AG9")
    (pin "AH11")
    (pin "AH12")
    (pin "AH14")
    (pin "AH15")
    (pin "AH16")
    (pin "AH17")
    (pin "AH19")
    (pin "AH2")
    (pin "AH20")
    (pin "AH22")
    (pin "AH23")
    (pin "AH24")
    (pin "AH25")
    (pin "AH26")
    (pin "AH29")
    (pin "AH31")
    (pin "AH5")
    (pin "AH7")
    (pin "AH8")
    (pin "AH9")
    (pin "AJ10")
    (pin "AJ11")
    (pin "AJ12")
    (pin "AJ13")
    (pin "AJ14")
    (pin "AJ15")
    (pin "AJ16")
    (pin "AJ17")
    (pin "AJ18")
    (pin "AJ19")
    (pin "AJ20")
    (pin "AJ21")
    (pin "AJ22")
    (pin "AJ23")
    (pin "AJ24")
    (pin "AJ25")
    (pin "AJ26")
    (pin "AJ7")
    (pin "AJ8")
    (pin "AJ9")
    (pin "AK11")
    (pin "AK14")
    (pin "AK15")
    (pin "AK16")
    (pin "AK17")
    (pin "AK20")
    (pin "AK23")
    (pin "AK24")
    (pin "AK25")
    (pin "AK26")
    (pin "AK7")
    (pin "AK8")
    (pin "AL11")
    (pin "AL12")
    (pin "AL14")
    (pin "AL15")
    (pin "AL17")
    (pin "AL18")
    (pin "AL2")
    (pin "AL20")
    (pin "AL21")
    (pin "AL23")
    (pin "AL24")
    (pin "AL26")
    (pin "AL29")
    (pin "AL31")
    (pin "AL5")
    (pin "AL7")
    (pin "AL8")
    (pin "AL9")
    (pin "AM26")
    (pin "AM7")
    (pin "B13")
    (pin "B15")
    (pin "B18")
    (pin "B2")
    (pin "B20")
    (pin "B24")
    (pin "B28")
    (pin "B31")
    (pin "B5")
    (pin "B9")
    (pin "E13")
    (pin "E15")
    (pin "E18")
    (pin "E2")
    (pin "E20")
    (pin "E24")
    (pin "E26")
    (pin "E28")
    (pin "E31")
    (pin "E5")
    (pin "E7")
    (pin "E9")
    (pin "G10")
    (pin "G11")
    (pin "G14")
    (pin "G15")
    (pin "G16")
    (pin "G17")
    (pin "G18")
    (pin "G19")
    (pin "G22")
    (pin "G23")
    (pin "G24")
    (pin "G9")
    (pin "H29")
    (pin "H4")
    (pin "J2")
    (pin "J28")
    (pin "J31")
    (pin "J5")
    (pin "K10")
    (pin "K11")
    (pin "K13")
    (pin "K20")
    (pin "K22")
    (pin "K23")
    (pin "L10")
    (pin "L11")
    (pin "L12")
    (pin "L13")
    (pin "L14")
    (pin "L15")
    (pin "L16")
    (pin "L17")
    (pin "L18")
    (pin "L19")
    (pin "L20")
    (pin "L21")
    (pin "L22")
    (pin "L23")
    (pin "L28")
    (pin "L5")
    (pin "M11")
    (pin "M12")
    (pin "M13")
    (pin "M14")
    (pin "M15")
    (pin "M16")
    (pin "M17")
    (pin "M18")
    (pin "M19")
    (pin "M20")
    (pin "M21")
    (pin "M22")
    (pin "N10")
    (pin "N11")
    (pin "N12")
    (pin "N13")
    (pin "N14")
    (pin "N15")
    (pin "N16")
    (pin "N17")
    (pin "N18")
    (pin "N19")
    (pin "N2")
    (pin "N20")
    (pin "N21")
    (pin "N22")
    (pin "N23")
    (pin "N28")
    (pin "N31")
    (pin "N5")
    (pin "P11")
    (pin "P12")
    (pin "P13")
    (pin "P14")
    (pin "P15")
    (pin "P16")
    (pin "P17")
    (pin "P18")
    (pin "P19")
    (pin "P20")
    (pin "P21")
    (pin "P22")
    (pin "R11")
    (pin "R12")
    (pin "R13")
    (pin "R14")
    (pin "R15")
    (pin "R16")
    (pin "R17")
    (pin "R18")
    (pin "R19")
    (pin "R2")
    (pin "R20")
    (pin "R21")
    (pin "R22")
    (pin "R28")
    (pin "R31")
    (pin "R5")
    (pin "T11")
    (pin "T12")
    (pin "T13")
    (pin "T14")
    (pin "T15")
    (pin "T16")
    (pin "T17")
    (pin "T18")
    (pin "T19")
    (pin "T20")
    (pin "T21")
    (pin "T22")
    (pin "U11")
    (pin "U12")
    (pin "U13")
    (pin "U14")
    (pin "U15")
    (pin "U16")
    (pin "U17")
    (pin "U18")
    (pin "U19")
    (pin "U20")
    (pin "U21")
    (pin "U22")
    (pin "V11")
    (pin "V12")
    (pin "V13")
    (pin "V14")
    (pin "V15")
    (pin "V16")
    (pin "V17")
    (pin "V18")
    (pin "V19")
    (pin "V2")
    (pin "V20")
    (pin "V21")
    (pin "V22")
    (pin "V28")
    (pin "V3")
    (pin "V30")
    (pin "V31")
    (pin "V5")
    (pin "W11")
    (pin "W12")
    (pin "W13")
    (pin "W14")
    (pin "W15")
    (pin "W16")
    (pin "W17")
    (pin "W18")
    (pin "W19")
    (pin "W20")
    (pin "W21")
    (pin "W22")
    (pin "W27")
    (pin "W6")
    (pin "Y10")
    (pin "Y11")
    (pin "Y12")
    (pin "Y13")
    (pin "Y14")
    (pin "Y15")
    (pin "Y16")
    (pin "Y17")
    (pin "Y18")
    (pin "Y19")
    (pin "Y2")
    (pin "Y20")
    (pin "Y21")
    (pin "Y22")
    (pin "Y23")
    (pin "Y31")
    (pin "A10")
    (pin "A11")
    (pin "A13")
    (pin "A14")
    (pin "A15")
    (pin "A16")
    (pin "A17")
    (pin "A2")
    (pin "A3")
    (pin "A4")
    (pin "A5")
    (pin "A7")
    (pin "A8")
    (pin "A9")
    (pin "B10")
    (pin "B11")
    (pin "B14")
    (pin "B16")
    (pin "B17")
    (pin "B3")
    (pin "B4")
    (pin "B7")
    (pin "B8")
    (pin "C10")
    (pin "C11")
    (pin "C13")
    (pin "C14")
    (pin "C15")
    (pin "C16")
    (pin "C17")
    (pin "C7")
    (pin "C8")
    (pin "C9")
    (pin "D10")
    (pin "D11")
    (pin "D13")
    (pin "D14")
    (pin "D15")
    (pin "D16")
    (pin "D17")
    (pin "D7")
    (pin "D8")
    (pin "D9")
    (pin "E10")
    (pin "E11")
    (pin "E14")
    (pin "E16")
    (pin "E8")
    (pin "F10")
    (pin "F11")
    (pin "F13")
    (pin "F14")
    (pin "F15")
    (pin "F16")
    (pin "F8")
    (pin "F9")
    (pin "K12")
    (pin "K14")
    (pin "K15")
    (pin "K16")
    (pin "A18")
    (pin "A19")
    (pin "A20")
    (pin "A22")
    (pin "A23")
    (pin "A24")
    (pin "A25")
    (pin "A26")
    (pin "A28")
    (pin "A29")
    (pin "A30")
    (pin "A31")
    (pin "B19")
    (pin "B22")
    (pin "B23")
    (pin "B25")
    (pin "B26")
    (pin "B29")
    (pin "B30")
    (pin "C18")
    (pin "C19")
    (pin "C20")
    (pin "C22")
    (pin "C23")
    (pin "C24")
    (pin "C25")
    (pin "C26")
    (pin "D18")
    (pin "D19")
    (pin "D20")
    (pin "D22")
    (pin "D23")
    (pin "D24")
    (pin "D25")
    (pin "D26")
    (pin "E17")
    (pin "E19")
    (pin "E22")
    (pin "E23")
    (pin "E25")
    (pin "F17")
    (pin "F18")
    (pin "F19")
    (pin "F20")
    (pin "F22")
    (pin "F23")
    (pin "F24")
    (pin "F25")
    (pin "K17")
    (pin "K18")
    (pin "K19")
    (pin "K21")
    (pin "B32")
    (pin "C28")
    (pin "C29")
    (pin "C30")
    (pin "C31")
    (pin "C32")
    (pin "D28")
    (pin "D29")
    (pin "D30")
    (pin "D31")
    (pin "D32")
    (pin "E29")
    (pin "E30")
    (pin "E32")
    (pin "F28")
    (pin "F29")
    (pin "F30")
    (pin "F31")
    (pin "F32")
    (pin "H27")
    (pin "H28")
    (pin "H30")
    (pin "H31")
    (pin "H32")
    (pin "J26")
    (pin "J27")
    (pin "J29")
    (pin "J30")
    (pin "J32")
    (pin "K26")
    (pin "K27")
    (pin "K28")
    (pin "K29")
    (pin "K30")
    (pin "K31")
    (pin "K32")
    (pin "L26")
    (pin "L27")
    (pin "L29")
    (pin "L30")
    (pin "L31")
    (pin "L32")
    (pin "M23")
    (pin "N26")
    (pin "N27")
    (pin "N29")
    (pin "N30")
    (pin "P23")
    (pin "P26")
    (pin "P27")
    (pin "R23")
    (pin "T23")
    (pin "AA23")
    (pin "AB26")
    (pin "AB27")
    (pin "AB28")
    (pin "AB29")
    (pin "AB30")
    (pin "AB31")
    (pin "AB32")
    (pin "AC26")
    (pin "AC27")
    (pin "AC28")
    (pin "AC30")
    (pin "AC31")
    (pin "AC32")
    (pin "AD26")
    (pin "AD27")
    (pin "AD29")
    (pin "AD30")
    (pin "AD32")
    (pin "AE27")
    (pin "AE28")
    (pin "AE29")
    (pin "AE30")
    (pin "AE31")
    (pin "AE32")
    (pin "N32")
    (pin "P28")
    (pin "P29")
    (pin "P30")
    (pin "P31")
    (pin "P32")
    (pin "R26")
    (pin "R27")
    (pin "R29")
    (pin "R30")
    (pin "R32")
    (pin "T26")
    (pin "T27")
    (pin "T28")
    (pin "T29")
    (pin "T30")
    (pin "T31")
    (pin "T32")
    (pin "U23")
    (pin "U26")
    (pin "U27")
    (pin "U28")
    (pin "U29")
    (pin "U30")
    (pin "U31")
    (pin "U32")
    (pin "V23")
    (pin "V26")
    (pin "V27")
    (pin "V29")
    (pin "V32")
    (pin "W23")
    (pin "W28")
    (pin "W29")
    (pin "W30")
    (pin "W31")
    (pin "W32")
    (pin "Y26")
    (pin "Y27")
    (pin "Y28")
    (pin "Y29")
    (pin "Y30")
    (pin "Y32")
    (pin "AB23")
    (pin "AC23")
    (pin "AG28")
    (pin "AG29")
    (pin "AG30")
    (pin "AG32")
    (pin "AH28")
    (pin "AH30")
    (pin "AH32")
    (pin "AJ28")
    (pin "AJ29")
    (pin "AJ30")
    (pin "AJ31")
    (pin "AJ32")
    (pin "AK28")
    (pin "AK29")
    (pin "AK30")
    (pin "AK31")
    (pin "AK32")
    (pin "AL28")
    (pin "AL30")
    (pin "AL32")
    (pin "AM28")
    (pin "AM29")
    (pin "AM30")
    (pin "AM31")
    (pin "AA10")
    (pin "AB1")
    (pin "AB2")
    (pin "AB3")
    (pin "AB4")
    (pin "AB5")
    (pin "AB6")
    (pin "AB7")
    (pin "AC1")
    (pin "AC2")
    (pin "AC3")
    (pin "AC5")
    (pin "AC6")
    (pin "AC7")
    (pin "AD1")
    (pin "AD3")
    (pin "AD4")
    (pin "AD6")
    (pin "AD7")
    (pin "AE1")
    (pin "AE2")
    (pin "AE3")
    (pin "AE4")
    (pin "AE5")
    (pin "AE6")
    (pin "N1")
    (pin "P1")
    (pin "P2")
    (pin "P3")
    (pin "P4")
    (pin "P5")
    (pin "R1")
    (pin "R3")
    (pin "R4")
    (pin "R6")
    (pin "R7")
    (pin "T1")
    (pin "T2")
    (pin "T3")
    (pin "T4")
    (pin "T5")
    (pin "T6")
    (pin "T7")
    (pin "U1")
    (pin "U10")
    (pin "U2")
    (pin "U3")
    (pin "U4")
    (pin "U5")
    (pin "U6")
    (pin "U7")
    (pin "V1")
    (pin "V10")
    (pin "V4")
    (pin "V6")
    (pin "V7")
    (pin "W1")
    (pin "W10")
    (pin "W2")
    (pin "W3")
    (pin "W4")
    (pin "W5")
    (pin "Y1")
    (pin "Y3")
    (pin "Y4")
    (pin "Y5")
    (pin "Y6")
    (pin "Y7")
    (pin "B1")
    (pin "C1")
    (pin "C2")
    (pin "C3")
    (pin "C4")
    (pin "C5")
    (pin "D1")
    (pin "D2")
    (pin "D3")
    (pin "D4")
    (pin "D5")
    (pin "E1")
    (pin "E3")
    (pin "E4")
    (pin "F1")
    (pin "F2")
    (pin "F3")
    (pin "F4")
    (pin "F5")
    (pin "H1")
    (pin "H2")
    (pin "H3")
    (pin "H5")
    (pin "H6")
    (pin "J1")
    (pin "J3")
    (pin "J4")
    (pin "J6")
    (pin "J7")
    (pin "K1")
    (pin "K2")
    (pin "K3")
    (pin "K4")
    (pin "K5")
    (pin "K6")
    (pin "K7")
    (pin "L1")
    (pin "L2")
    (pin "L3")
    (pin "L4")
    (pin "L6")
    (pin "L7")
    (pin "M10")
    (pin "N3")
    (pin "N4")
    (pin "N6")
    (pin "N7")
    (pin "P10")
    (pin "P6")
    (pin "P7")
    (pin "R10")
    (pin "T10")
    (pin "AB10")
    (pin "AC10")
    (pin "AG1")
    (pin "AG3")
    (pin "AG4")
    (pin "AH1")
    (pin "AH3")
    (pin "AH4")
    (pin "AJ1")
    (pin "AJ2")
    (pin "AJ3")
    (pin "AJ4")
    (pin "AK1")
    (pin "AK2")
    (pin "AK3")
    (pin "AK4")
    (pin "AL1")
    (pin "AL3")
    (pin "AL4")
    (pin "AM2")
    (pin "AM3")
    (pin "AM4")
    (pin "AG5")
    (pin "AJ5")
    (pin "AK5")
    (pin "AM5")
    (pin "AK10")
    (pin "AK12")
    (pin "AK13")
    (pin "AK9")
    (pin "AM11")
    (pin "AM12")
    (pin "AM14")
    (pin "AM15")
    (pin "AM8")
    (pin "AM9")
    (pin "AK18")
    (pin "AK19")
    (pin "AK21")
    (pin "AK22")
    (pin "AM17")
    (pin "AM18")
    (pin "AM20")
    (pin "AM21")
    (pin "AM23")
    (pin "AM24")
    (instances
      (project "ecp5-dc-scm"
        (path ""
          (reference "U21") (unit 3)
        )
      )
    )
  )

  (symbol (lib_id "antmicroFPGAChips:ECP5_LFE5UM5G-85") (at 303.53 55.88 0) (unit 7)
    (in_bom yes) (on_board yes) (dnp no)
    (property "Reference" "U21" (at 308.61 41.91 0)
      (effects (font (size 1.524 1.524)) (justify left))
    )
    (property "Value" "ECP5UM5G_85_CABGA756" (at 306.07 220.345 0)
      (effects (font (size 1.524 1.524)) (justify left))
    )
    (property "Footprint" "antmicro-footprints:BGA-1024-756_27x27mm_Layout32x32_P0.8mm" (at 303.53 55.88 0)
      (effects (font (size 1.27 1.27)) hide)
    )
    (property "Datasheet" "https://www.latticesemi.com/-/media/LatticeSemi/Documents/DataSheets/ECP5/FPGA-DS-02012-2-2-ECP5-ECP5G-Family-Data-Sheet.ashx?document_id=50461" (at 303.53 55.88 0)
      (effects (font (size 1.27 1.27)) hide)
    )
    (property "MPN" "LFE5UM5G-85F-8BG756C" (at 307.34 57.15 0)
      (effects (font (size 1.524 1.524)) (justify right) hide)
    )
    (property "Manufacturer" "Lattice Semiconductor" (at 332.232 130.7846 0)
      (effects (font (size 1.27 1.27)) (justify left) hide)
    )
    (property "Author" "Antmicro" (at 381 74.93 0)
      (effects (font (size 1.27 1.27) (thickness 0.15)) (justify left bottom) hide)
    )
    (property "License" "Apache-2.0" (at 381 77.47 0)
      (effects (font (size 1.27 1.27) (thickness 0.15)) (justify left bottom) hide)
    )
    (pin "AA11")
    (pin "AA12")
    (pin "AA13")
    (pin "AA14")
    (pin "AA15")
    (pin "AA16")
    (pin "AA17")
    (pin "AA18")
    (pin "AA19")
    (pin "AA20")
    (pin "AA21")
    (pin "AA22")
    (pin "AB11")
    (pin "AB12")
    (pin "AB13")
    (pin "AB14")
    (pin "AB15")
    (pin "AB16")
    (pin "AB17")
    (pin "AB18")
    (pin "AB19")
    (pin "AB20")
    (pin "AB21")
    (pin "AB22")
    (pin "AC11")
    (pin "AC12")
    (pin "AC13")
    (pin "AC14")
    (pin "AC15")
    (pin "AC16")
    (pin "AC17")
    (pin "AC18")
    (pin "AC19")
    (pin "AC20")
    (pin "AC21")
    (pin "AC22")
    (pin "AC29")
    (pin "AC4")
    (pin "AD2")
    (pin "AD28")
    (pin "AD31")
    (pin "AD5")
    (pin "AE26")
    (pin "AE7")
    (pin "AF11")
    (pin "AF12")
    (pin "AF14")
    (pin "AF15")
    (pin "AF16")
    (pin "AF17")
    (pin "AF19")
    (pin "AF20")
    (pin "AF22")
    (pin "AF23")
    (pin "AG11")
    (pin "AG12")
    (pin "AG14")
    (pin "AG15")
    (pin "AG16")
    (pin "AG17")
    (pin "AG19")
    (pin "AG2")
    (pin "AG20")
    (pin "AG22")
    (pin "AG23")
    (pin "AG24")
    (pin "AG31")
    (pin "AG9")
    (pin "AH11")
    (pin "AH12")
    (pin "AH14")
    (pin "AH15")
    (pin "AH16")
    (pin "AH17")
    (pin "AH19")
    (pin "AH2")
    (pin "AH20")
    (pin "AH22")
    (pin "AH23")
    (pin "AH24")
    (pin "AH25")
    (pin "AH26")
    (pin "AH29")
    (pin "AH31")
    (pin "AH5")
    (pin "AH7")
    (pin "AH8")
    (pin "AH9")
    (pin "AJ10")
    (pin "AJ11")
    (pin "AJ12")
    (pin "AJ13")
    (pin "AJ14")
    (pin "AJ15")
    (pin "AJ16")
    (pin "AJ17")
    (pin "AJ18")
    (pin "AJ19")
    (pin "AJ20")
    (pin "AJ21")
    (pin "AJ22")
    (pin "AJ23")
    (pin "AJ24")
    (pin "AJ25")
    (pin "AJ26")
    (pin "AJ7")
    (pin "AJ8")
    (pin "AJ9")
    (pin "AK11")
    (pin "AK14")
    (pin "AK15")
    (pin "AK16")
    (pin "AK17")
    (pin "AK20")
    (pin "AK23")
    (pin "AK24")
    (pin "AK25")
    (pin "AK26")
    (pin "AK7")
    (pin "AK8")
    (pin "AL11")
    (pin "AL12")
    (pin "AL14")
    (pin "AL15")
    (pin "AL17")
    (pin "AL18")
    (pin "AL2")
    (pin "AL20")
    (pin "AL21")
    (pin "AL23")
    (pin "AL24")
    (pin "AL26")
    (pin "AL29")
    (pin "AL31")
    (pin "AL5")
    (pin "AL7")
    (pin "AL8")
    (pin "AL9")
    (pin "AM26")
    (pin "AM7")
    (pin "B13")
    (pin "B15")
    (pin "B18")
    (pin "B2")
    (pin "B20")
    (pin "B24")
    (pin "B28")
    (pin "B31")
    (pin "B5")
    (pin "B9")
    (pin "E13")
    (pin "E15")
    (pin "E18")
    (pin "E2")
    (pin "E20")
    (pin "E24")
    (pin "E26")
    (pin "E28")
    (pin "E31")
    (pin "E5")
    (pin "E7")
    (pin "E9")
    (pin "G10")
    (pin "G11")
    (pin "G14")
    (pin "G15")
    (pin "G16")
    (pin "G17")
    (pin "G18")
    (pin "G19")
    (pin "G22")
    (pin "G23")
    (pin "G24")
    (pin "G9")
    (pin "H29")
    (pin "H4")
    (pin "J2")
    (pin "J28")
    (pin "J31")
    (pin "J5")
    (pin "K10")
    (pin "K11")
    (pin "K13")
    (pin "K20")
    (pin "K22")
    (pin "K23")
    (pin "L10")
    (pin "L11")
    (pin "L12")
    (pin "L13")
    (pin "L14")
    (pin "L15")
    (pin "L16")
    (pin "L17")
    (pin "L18")
    (pin "L19")
    (pin "L20")
    (pin "L21")
    (pin "L22")
    (pin "L23")
    (pin "L28")
    (pin "L5")
    (pin "M11")
    (pin "M12")
    (pin "M13")
    (pin "M14")
    (pin "M15")
    (pin "M16")
    (pin "M17")
    (pin "M18")
    (pin "M19")
    (pin "M20")
    (pin "M21")
    (pin "M22")
    (pin "N10")
    (pin "N11")
    (pin "N12")
    (pin "N13")
    (pin "N14")
    (pin "N15")
    (pin "N16")
    (pin "N17")
    (pin "N18")
    (pin "N19")
    (pin "N2")
    (pin "N20")
    (pin "N21")
    (pin "N22")
    (pin "N23")
    (pin "N28")
    (pin "N31")
    (pin "N5")
    (pin "P11")
    (pin "P12")
    (pin "P13")
    (pin "P14")
    (pin "P15")
    (pin "P16")
    (pin "P17")
    (pin "P18")
    (pin "P19")
    (pin "P20")
    (pin "P21")
    (pin "P22")
    (pin "R11")
    (pin "R12")
    (pin "R13")
    (pin "R14")
    (pin "R15")
    (pin "R16")
    (pin "R17")
    (pin "R18")
    (pin "R19")
    (pin "R2")
    (pin "R20")
    (pin "R21")
    (pin "R22")
    (pin "R28")
    (pin "R31")
    (pin "R5")
    (pin "T11")
    (pin "T12")
    (pin "T13")
    (pin "T14")
    (pin "T15")
    (pin "T16")
    (pin "T17")
    (pin "T18")
    (pin "T19")
    (pin "T20")
    (pin "T21")
    (pin "T22")
    (pin "U11")
    (pin "U12")
    (pin "U13")
    (pin "U14")
    (pin "U15")
    (pin "U16")
    (pin "U17")
    (pin "U18")
    (pin "U19")
    (pin "U20")
    (pin "U21")
    (pin "U22")
    (pin "V11")
    (pin "V12")
    (pin "V13")
    (pin "V14")
    (pin "V15")
    (pin "V16")
    (pin "V17")
    (pin "V18")
    (pin "V19")
    (pin "V2")
    (pin "V20")
    (pin "V21")
    (pin "V22")
    (pin "V28")
    (pin "V3")
    (pin "V30")
    (pin "V31")
    (pin "V5")
    (pin "W11")
    (pin "W12")
    (pin "W13")
    (pin "W14")
    (pin "W15")
    (pin "W16")
    (pin "W17")
    (pin "W18")
    (pin "W19")
    (pin "W20")
    (pin "W21")
    (pin "W22")
    (pin "W27")
    (pin "W6")
    (pin "Y10")
    (pin "Y11")
    (pin "Y12")
    (pin "Y13")
    (pin "Y14")
    (pin "Y15")
    (pin "Y16")
    (pin "Y17")
    (pin "Y18")
    (pin "Y19")
    (pin "Y2")
    (pin "Y20")
    (pin "Y21")
    (pin "Y22")
    (pin "Y23")
    (pin "Y31")
    (pin "A10")
    (pin "A11")
    (pin "A13")
    (pin "A14")
    (pin "A15")
    (pin "A16")
    (pin "A17")
    (pin "A2")
    (pin "A3")
    (pin "A4")
    (pin "A5")
    (pin "A7")
    (pin "A8")
    (pin "A9")
    (pin "B10")
    (pin "B11")
    (pin "B14")
    (pin "B16")
    (pin "B17")
    (pin "B3")
    (pin "B4")
    (pin "B7")
    (pin "B8")
    (pin "C10")
    (pin "C11")
    (pin "C13")
    (pin "C14")
    (pin "C15")
    (pin "C16")
    (pin "C17")
    (pin "C7")
    (pin "C8")
    (pin "C9")
    (pin "D10")
    (pin "D11")
    (pin "D13")
    (pin "D14")
    (pin "D15")
    (pin "D16")
    (pin "D17")
    (pin "D7")
    (pin "D8")
    (pin "D9")
    (pin "E10")
    (pin "E11")
    (pin "E14")
    (pin "E16")
    (pin "E8")
    (pin "F10")
    (pin "F11")
    (pin "F13")
    (pin "F14")
    (pin "F15")
    (pin "F16")
    (pin "F8")
    (pin "F9")
    (pin "K12")
    (pin "K14")
    (pin "K15")
    (pin "K16")
    (pin "A18")
    (pin "A19")
    (pin "A20")
    (pin "A22")
    (pin "A23")
    (pin "A24")
    (pin "A25")
    (pin "A26")
    (pin "A28")
    (pin "A29")
    (pin "A30")
    (pin "A31")
    (pin "B19")
    (pin "B22")
    (pin "B23")
    (pin "B25")
    (pin "B26")
    (pin "B29")
    (pin "B30")
    (pin "C18")
    (pin "C19")
    (pin "C20")
    (pin "C22")
    (pin "C23")
    (pin "C24")
    (pin "C25")
    (pin "C26")
    (pin "D18")
    (pin "D19")
    (pin "D20")
    (pin "D22")
    (pin "D23")
    (pin "D24")
    (pin "D25")
    (pin "D26")
    (pin "E17")
    (pin "E19")
    (pin "E22")
    (pin "E23")
    (pin "E25")
    (pin "F17")
    (pin "F18")
    (pin "F19")
    (pin "F20")
    (pin "F22")
    (pin "F23")
    (pin "F24")
    (pin "F25")
    (pin "K17")
    (pin "K18")
    (pin "K19")
    (pin "K21")
    (pin "B32")
    (pin "C28")
    (pin "C29")
    (pin "C30")
    (pin "C31")
    (pin "C32")
    (pin "D28")
    (pin "D29")
    (pin "D30")
    (pin "D31")
    (pin "D32")
    (pin "E29")
    (pin "E30")
    (pin "E32")
    (pin "F28")
    (pin "F29")
    (pin "F30")
    (pin "F31")
    (pin "F32")
    (pin "H27")
    (pin "H28")
    (pin "H30")
    (pin "H31")
    (pin "H32")
    (pin "J26")
    (pin "J27")
    (pin "J29")
    (pin "J30")
    (pin "J32")
    (pin "K26")
    (pin "K27")
    (pin "K28")
    (pin "K29")
    (pin "K30")
    (pin "K31")
    (pin "K32")
    (pin "L26")
    (pin "L27")
    (pin "L29")
    (pin "L30")
    (pin "L31")
    (pin "L32")
    (pin "M23")
    (pin "N26")
    (pin "N27")
    (pin "N29")
    (pin "N30")
    (pin "P23")
    (pin "P26")
    (pin "P27")
    (pin "R23")
    (pin "T23")
    (pin "AA23")
    (pin "AB26")
    (pin "AB27")
    (pin "AB28")
    (pin "AB29")
    (pin "AB30")
    (pin "AB31")
    (pin "AB32")
    (pin "AC26")
    (pin "AC27")
    (pin "AC28")
    (pin "AC30")
    (pin "AC31")
    (pin "AC32")
    (pin "AD26")
    (pin "AD27")
    (pin "AD29")
    (pin "AD30")
    (pin "AD32")
    (pin "AE27")
    (pin "AE28")
    (pin "AE29")
    (pin "AE30")
    (pin "AE31")
    (pin "AE32")
    (pin "N32")
    (pin "P28")
    (pin "P29")
    (pin "P30")
    (pin "P31")
    (pin "P32")
    (pin "R26")
    (pin "R27")
    (pin "R29")
    (pin "R30")
    (pin "R32")
    (pin "T26")
    (pin "T27")
    (pin "T28")
    (pin "T29")
    (pin "T30")
    (pin "T31")
    (pin "T32")
    (pin "U23")
    (pin "U26")
    (pin "U27")
    (pin "U28")
    (pin "U29")
    (pin "U30")
    (pin "U31")
    (pin "U32")
    (pin "V23")
    (pin "V26")
    (pin "V27")
    (pin "V29")
    (pin "V32")
    (pin "W23")
    (pin "W28")
    (pin "W29")
    (pin "W30")
    (pin "W31")
    (pin "W32")
    (pin "Y26")
    (pin "Y27")
    (pin "Y28")
    (pin "Y29")
    (pin "Y30")
    (pin "Y32")
    (pin "AB23")
    (pin "AC23")
    (pin "AG28")
    (pin "AG29")
    (pin "AG30")
    (pin "AG32")
    (pin "AH28")
    (pin "AH30")
    (pin "AH32")
    (pin "AJ28")
    (pin "AJ29")
    (pin "AJ30")
    (pin "AJ31")
    (pin "AJ32")
    (pin "AK28")
    (pin "AK29")
    (pin "AK30")
    (pin "AK31")
    (pin "AK32")
    (pin "AL28")
    (pin "AL30")
    (pin "AL32")
    (pin "AM28")
    (pin "AM29")
    (pin "AM30")
    (pin "AM31")
    (pin "AA10")
    (pin "AB1")
    (pin "AB2")
    (pin "AB3")
    (pin "AB4")
    (pin "AB5")
    (pin "AB6")
    (pin "AB7")
    (pin "AC1")
    (pin "AC2")
    (pin "AC3")
    (pin "AC5")
    (pin "AC6")
    (pin "AC7")
    (pin "AD1")
    (pin "AD3")
    (pin "AD4")
    (pin "AD6")
    (pin "AD7")
    (pin "AE1")
    (pin "AE2")
    (pin "AE3")
    (pin "AE4")
    (pin "AE5")
    (pin "AE6")
    (pin "N1")
    (pin "P1")
    (pin "P2")
    (pin "P3")
    (pin "P4")
    (pin "P5")
    (pin "R1")
    (pin "R3")
    (pin "R4")
    (pin "R6")
    (pin "R7")
    (pin "T1")
    (pin "T2")
    (pin "T3")
    (pin "T4")
    (pin "T5")
    (pin "T6")
    (pin "T7")
    (pin "U1")
    (pin "U10")
    (pin "U2")
    (pin "U3")
    (pin "U4")
    (pin "U5")
    (pin "U6")
    (pin "U7")
    (pin "V1")
    (pin "V10")
    (pin "V4")
    (pin "V6")
    (pin "V7")
    (pin "W1")
    (pin "W10")
    (pin "W2")
    (pin "W3")
    (pin "W4")
    (pin "W5")
    (pin "Y1")
    (pin "Y3")
    (pin "Y4")
    (pin "Y5")
    (pin "Y6")
    (pin "Y7")
    (pin "B1")
    (pin "C1")
    (pin "C2")
    (pin "C3")
    (pin "C4")
    (pin "C5")
    (pin "D1")
    (pin "D2")
    (pin "D3")
    (pin "D4")
    (pin "D5")
    (pin "E1")
    (pin "E3")
    (pin "E4")
    (pin "F1")
    (pin "F2")
    (pin "F3")
    (pin "F4")
    (pin "F5")
    (pin "H1")
    (pin "H2")
    (pin "H3")
    (pin "H5")
    (pin "H6")
    (pin "J1")
    (pin "J3")
    (pin "J4")
    (pin "J6")
    (pin "J7")
    (pin "K1")
    (pin "K2")
    (pin "K3")
    (pin "K4")
    (pin "K5")
    (pin "K6")
    (pin "K7")
    (pin "L1")
    (pin "L2")
    (pin "L3")
    (pin "L4")
    (pin "L6")
    (pin "L7")
    (pin "M10")
    (pin "N3")
    (pin "N4")
    (pin "N6")
    (pin "N7")
    (pin "P10")
    (pin "P6")
    (pin "P7")
    (pin "R10")
    (pin "T10")
    (pin "AB10")
    (pin "AC10")
    (pin "AG1")
    (pin "AG3")
    (pin "AG4")
    (pin "AH1")
    (pin "AH3")
    (pin "AH4")
    (pin "AJ1")
    (pin "AJ2")
    (pin "AJ3")
    (pin "AJ4")
    (pin "AK1")
    (pin "AK2")
    (pin "AK3")
    (pin "AK4")
    (pin "AL1")
    (pin "AL3")
    (pin "AL4")
    (pin "AM2")
    (pin "AM3")
    (pin "AM4")
    (pin "AG5")
    (pin "AJ5")
    (pin "AK5")
    (pin "AM5")
    (pin "AK10")
    (pin "AK12")
    (pin "AK13")
    (pin "AK9")
    (pin "AM11")
    (pin "AM12")
    (pin "AM14")
    (pin "AM15")
    (pin "AM8")
    (pin "AM9")
    (pin "AK18")
    (pin "AK19")
    (pin "AK21")
    (pin "AK22")
    (pin "AM17")
    (pin "AM18")
    (pin "AM20")
    (pin "AM21")
    (pin "AM23")
    (pin "AM24")
    (instances
      (project "ecp5-dc-scm"
        (path ""
          (reference "U21") (unit 7)
        )
      )
    )
  )

  (symbol (lib_id "antmicroFPGAChips:ECP5_LFE5UM5G-85") (at 93.98 213.36 0) (unit 6)
    (in_bom yes) (on_board yes) (dnp no) (fields_autoplaced)
    (property "Reference" "U21" (at 107.95 205.74 0)
      (effects (font (size 1.524 1.524)))
    )
    (property "Value" "ECP5UM5G_85_CABGA756" (at 107.95 208.28 0)
      (effects (font (size 1.524 1.524)))
    )
    (property "Footprint" "antmicro-footprints:BGA-1024-756_27x27mm_Layout32x32_P0.8mm" (at 93.98 213.36 0)
      (effects (font (size 1.27 1.27)) hide)
    )
    (property "Datasheet" "https://www.latticesemi.com/-/media/LatticeSemi/Documents/DataSheets/ECP5/FPGA-DS-02012-2-2-ECP5-ECP5G-Family-Data-Sheet.ashx?document_id=50461" (at 93.98 213.36 0)
      (effects (font (size 1.27 1.27)) hide)
    )
    (property "MPN" "LFE5UM5G-85F-8BG756C" (at 97.79 214.63 0)
      (effects (font (size 1.524 1.524)) (justify right) hide)
    )
    (property "Manufacturer" "Lattice Semiconductor" (at 117.602 237.4646 0)
      (effects (font (size 1.27 1.27)) (justify left) hide)
    )
    (property "Author" "Antmicro" (at 171.45 232.41 0)
      (effects (font (size 1.27 1.27) (thickness 0.15)) (justify left bottom) hide)
    )
    (property "License" "Apache-2.0" (at 171.45 234.95 0)
      (effects (font (size 1.27 1.27) (thickness 0.15)) (justify left bottom) hide)
    )
    (pin "AA11")
    (pin "AA12")
    (pin "AA13")
    (pin "AA14")
    (pin "AA15")
    (pin "AA16")
    (pin "AA17")
    (pin "AA18")
    (pin "AA19")
    (pin "AA20")
    (pin "AA21")
    (pin "AA22")
    (pin "AB11")
    (pin "AB12")
    (pin "AB13")
    (pin "AB14")
    (pin "AB15")
    (pin "AB16")
    (pin "AB17")
    (pin "AB18")
    (pin "AB19")
    (pin "AB20")
    (pin "AB21")
    (pin "AB22")
    (pin "AC11")
    (pin "AC12")
    (pin "AC13")
    (pin "AC14")
    (pin "AC15")
    (pin "AC16")
    (pin "AC17")
    (pin "AC18")
    (pin "AC19")
    (pin "AC20")
    (pin "AC21")
    (pin "AC22")
    (pin "AC29")
    (pin "AC4")
    (pin "AD2")
    (pin "AD28")
    (pin "AD31")
    (pin "AD5")
    (pin "AE26")
    (pin "AE7")
    (pin "AF11")
    (pin "AF12")
    (pin "AF14")
    (pin "AF15")
    (pin "AF16")
    (pin "AF17")
    (pin "AF19")
    (pin "AF20")
    (pin "AF22")
    (pin "AF23")
    (pin "AG11")
    (pin "AG12")
    (pin "AG14")
    (pin "AG15")
    (pin "AG16")
    (pin "AG17")
    (pin "AG19")
    (pin "AG2")
    (pin "AG20")
    (pin "AG22")
    (pin "AG23")
    (pin "AG24")
    (pin "AG31")
    (pin "AG9")
    (pin "AH11")
    (pin "AH12")
    (pin "AH14")
    (pin "AH15")
    (pin "AH16")
    (pin "AH17")
    (pin "AH19")
    (pin "AH2")
    (pin "AH20")
    (pin "AH22")
    (pin "AH23")
    (pin "AH24")
    (pin "AH25")
    (pin "AH26")
    (pin "AH29")
    (pin "AH31")
    (pin "AH5")
    (pin "AH7")
    (pin "AH8")
    (pin "AH9")
    (pin "AJ10")
    (pin "AJ11")
    (pin "AJ12")
    (pin "AJ13")
    (pin "AJ14")
    (pin "AJ15")
    (pin "AJ16")
    (pin "AJ17")
    (pin "AJ18")
    (pin "AJ19")
    (pin "AJ20")
    (pin "AJ21")
    (pin "AJ22")
    (pin "AJ23")
    (pin "AJ24")
    (pin "AJ25")
    (pin "AJ26")
    (pin "AJ7")
    (pin "AJ8")
    (pin "AJ9")
    (pin "AK11")
    (pin "AK14")
    (pin "AK15")
    (pin "AK16")
    (pin "AK17")
    (pin "AK20")
    (pin "AK23")
    (pin "AK24")
    (pin "AK25")
    (pin "AK26")
    (pin "AK7")
    (pin "AK8")
    (pin "AL11")
    (pin "AL12")
    (pin "AL14")
    (pin "AL15")
    (pin "AL17")
    (pin "AL18")
    (pin "AL2")
    (pin "AL20")
    (pin "AL21")
    (pin "AL23")
    (pin "AL24")
    (pin "AL26")
    (pin "AL29")
    (pin "AL31")
    (pin "AL5")
    (pin "AL7")
    (pin "AL8")
    (pin "AL9")
    (pin "AM26")
    (pin "AM7")
    (pin "B13")
    (pin "B15")
    (pin "B18")
    (pin "B2")
    (pin "B20")
    (pin "B24")
    (pin "B28")
    (pin "B31")
    (pin "B5")
    (pin "B9")
    (pin "E13")
    (pin "E15")
    (pin "E18")
    (pin "E2")
    (pin "E20")
    (pin "E24")
    (pin "E26")
    (pin "E28")
    (pin "E31")
    (pin "E5")
    (pin "E7")
    (pin "E9")
    (pin "G10")
    (pin "G11")
    (pin "G14")
    (pin "G15")
    (pin "G16")
    (pin "G17")
    (pin "G18")
    (pin "G19")
    (pin "G22")
    (pin "G23")
    (pin "G24")
    (pin "G9")
    (pin "H29")
    (pin "H4")
    (pin "J2")
    (pin "J28")
    (pin "J31")
    (pin "J5")
    (pin "K10")
    (pin "K11")
    (pin "K13")
    (pin "K20")
    (pin "K22")
    (pin "K23")
    (pin "L10")
    (pin "L11")
    (pin "L12")
    (pin "L13")
    (pin "L14")
    (pin "L15")
    (pin "L16")
    (pin "L17")
    (pin "L18")
    (pin "L19")
    (pin "L20")
    (pin "L21")
    (pin "L22")
    (pin "L23")
    (pin "L28")
    (pin "L5")
    (pin "M11")
    (pin "M12")
    (pin "M13")
    (pin "M14")
    (pin "M15")
    (pin "M16")
    (pin "M17")
    (pin "M18")
    (pin "M19")
    (pin "M20")
    (pin "M21")
    (pin "M22")
    (pin "N10")
    (pin "N11")
    (pin "N12")
    (pin "N13")
    (pin "N14")
    (pin "N15")
    (pin "N16")
    (pin "N17")
    (pin "N18")
    (pin "N19")
    (pin "N2")
    (pin "N20")
    (pin "N21")
    (pin "N22")
    (pin "N23")
    (pin "N28")
    (pin "N31")
    (pin "N5")
    (pin "P11")
    (pin "P12")
    (pin "P13")
    (pin "P14")
    (pin "P15")
    (pin "P16")
    (pin "P17")
    (pin "P18")
    (pin "P19")
    (pin "P20")
    (pin "P21")
    (pin "P22")
    (pin "R11")
    (pin "R12")
    (pin "R13")
    (pin "R14")
    (pin "R15")
    (pin "R16")
    (pin "R17")
    (pin "R18")
    (pin "R19")
    (pin "R2")
    (pin "R20")
    (pin "R21")
    (pin "R22")
    (pin "R28")
    (pin "R31")
    (pin "R5")
    (pin "T11")
    (pin "T12")
    (pin "T13")
    (pin "T14")
    (pin "T15")
    (pin "T16")
    (pin "T17")
    (pin "T18")
    (pin "T19")
    (pin "T20")
    (pin "T21")
    (pin "T22")
    (pin "U11")
    (pin "U12")
    (pin "U13")
    (pin "U14")
    (pin "U15")
    (pin "U16")
    (pin "U17")
    (pin "U18")
    (pin "U19")
    (pin "U20")
    (pin "U21")
    (pin "U22")
    (pin "V11")
    (pin "V12")
    (pin "V13")
    (pin "V14")
    (pin "V15")
    (pin "V16")
    (pin "V17")
    (pin "V18")
    (pin "V19")
    (pin "V2")
    (pin "V20")
    (pin "V21")
    (pin "V22")
    (pin "V28")
    (pin "V3")
    (pin "V30")
    (pin "V31")
    (pin "V5")
    (pin "W11")
    (pin "W12")
    (pin "W13")
    (pin "W14")
    (pin "W15")
    (pin "W16")
    (pin "W17")
    (pin "W18")
    (pin "W19")
    (pin "W20")
    (pin "W21")
    (pin "W22")
    (pin "W27")
    (pin "W6")
    (pin "Y10")
    (pin "Y11")
    (pin "Y12")
    (pin "Y13")
    (pin "Y14")
    (pin "Y15")
    (pin "Y16")
    (pin "Y17")
    (pin "Y18")
    (pin "Y19")
    (pin "Y2")
    (pin "Y20")
    (pin "Y21")
    (pin "Y22")
    (pin "Y23")
    (pin "Y31")
    (pin "A10")
    (pin "A11")
    (pin "A13")
    (pin "A14")
    (pin "A15")
    (pin "A16")
    (pin "A17")
    (pin "A2")
    (pin "A3")
    (pin "A4")
    (pin "A5")
    (pin "A7")
    (pin "A8")
    (pin "A9")
    (pin "B10")
    (pin "B11")
    (pin "B14")
    (pin "B16")
    (pin "B17")
    (pin "B3")
    (pin "B4")
    (pin "B7")
    (pin "B8")
    (pin "C10")
    (pin "C11")
    (pin "C13")
    (pin "C14")
    (pin "C15")
    (pin "C16")
    (pin "C17")
    (pin "C7")
    (pin "C8")
    (pin "C9")
    (pin "D10")
    (pin "D11")
    (pin "D13")
    (pin "D14")
    (pin "D15")
    (pin "D16")
    (pin "D17")
    (pin "D7")
    (pin "D8")
    (pin "D9")
    (pin "E10")
    (pin "E11")
    (pin "E14")
    (pin "E16")
    (pin "E8")
    (pin "F10")
    (pin "F11")
    (pin "F13")
    (pin "F14")
    (pin "F15")
    (pin "F16")
    (pin "F8")
    (pin "F9")
    (pin "K12")
    (pin "K14")
    (pin "K15")
    (pin "K16")
    (pin "A18")
    (pin "A19")
    (pin "A20")
    (pin "A22")
    (pin "A23")
    (pin "A24")
    (pin "A25")
    (pin "A26")
    (pin "A28")
    (pin "A29")
    (pin "A30")
    (pin "A31")
    (pin "B19")
    (pin "B22")
    (pin "B23")
    (pin "B25")
    (pin "B26")
    (pin "B29")
    (pin "B30")
    (pin "C18")
    (pin "C19")
    (pin "C20")
    (pin "C22")
    (pin "C23")
    (pin "C24")
    (pin "C25")
    (pin "C26")
    (pin "D18")
    (pin "D19")
    (pin "D20")
    (pin "D22")
    (pin "D23")
    (pin "D24")
    (pin "D25")
    (pin "D26")
    (pin "E17")
    (pin "E19")
    (pin "E22")
    (pin "E23")
    (pin "E25")
    (pin "F17")
    (pin "F18")
    (pin "F19")
    (pin "F20")
    (pin "F22")
    (pin "F23")
    (pin "F24")
    (pin "F25")
    (pin "K17")
    (pin "K18")
    (pin "K19")
    (pin "K21")
    (pin "B32")
    (pin "C28")
    (pin "C29")
    (pin "C30")
    (pin "C31")
    (pin "C32")
    (pin "D28")
    (pin "D29")
    (pin "D30")
    (pin "D31")
    (pin "D32")
    (pin "E29")
    (pin "E30")
    (pin "E32")
    (pin "F28")
    (pin "F29")
    (pin "F30")
    (pin "F31")
    (pin "F32")
    (pin "H27")
    (pin "H28")
    (pin "H30")
    (pin "H31")
    (pin "H32")
    (pin "J26")
    (pin "J27")
    (pin "J29")
    (pin "J30")
    (pin "J32")
    (pin "K26")
    (pin "K27")
    (pin "K28")
    (pin "K29")
    (pin "K30")
    (pin "K31")
    (pin "K32")
    (pin "L26")
    (pin "L27")
    (pin "L29")
    (pin "L30")
    (pin "L31")
    (pin "L32")
    (pin "M23")
    (pin "N26")
    (pin "N27")
    (pin "N29")
    (pin "N30")
    (pin "P23")
    (pin "P26")
    (pin "P27")
    (pin "R23")
    (pin "T23")
    (pin "AA23")
    (pin "AB26")
    (pin "AB27")
    (pin "AB28")
    (pin "AB29")
    (pin "AB30")
    (pin "AB31")
    (pin "AB32")
    (pin "AC26")
    (pin "AC27")
    (pin "AC28")
    (pin "AC30")
    (pin "AC31")
    (pin "AC32")
    (pin "AD26")
    (pin "AD27")
    (pin "AD29")
    (pin "AD30")
    (pin "AD32")
    (pin "AE27")
    (pin "AE28")
    (pin "AE29")
    (pin "AE30")
    (pin "AE31")
    (pin "AE32")
    (pin "N32")
    (pin "P28")
    (pin "P29")
    (pin "P30")
    (pin "P31")
    (pin "P32")
    (pin "R26")
    (pin "R27")
    (pin "R29")
    (pin "R30")
    (pin "R32")
    (pin "T26")
    (pin "T27")
    (pin "T28")
    (pin "T29")
    (pin "T30")
    (pin "T31")
    (pin "T32")
    (pin "U23")
    (pin "U26")
    (pin "U27")
    (pin "U28")
    (pin "U29")
    (pin "U30")
    (pin "U31")
    (pin "U32")
    (pin "V23")
    (pin "V26")
    (pin "V27")
    (pin "V29")
    (pin "V32")
    (pin "W23")
    (pin "W28")
    (pin "W29")
    (pin "W30")
    (pin "W31")
    (pin "W32")
    (pin "Y26")
    (pin "Y27")
    (pin "Y28")
    (pin "Y29")
    (pin "Y30")
    (pin "Y32")
    (pin "AB23")
    (pin "AC23")
    (pin "AG28")
    (pin "AG29")
    (pin "AG30")
    (pin "AG32")
    (pin "AH28")
    (pin "AH30")
    (pin "AH32")
    (pin "AJ28")
    (pin "AJ29")
    (pin "AJ30")
    (pin "AJ31")
    (pin "AJ32")
    (pin "AK28")
    (pin "AK29")
    (pin "AK30")
    (pin "AK31")
    (pin "AK32")
    (pin "AL28")
    (pin "AL30")
    (pin "AL32")
    (pin "AM28")
    (pin "AM29")
    (pin "AM30")
    (pin "AM31")
    (pin "AA10")
    (pin "AB1")
    (pin "AB2")
    (pin "AB3")
    (pin "AB4")
    (pin "AB5")
    (pin "AB6")
    (pin "AB7")
    (pin "AC1")
    (pin "AC2")
    (pin "AC3")
    (pin "AC5")
    (pin "AC6")
    (pin "AC7")
    (pin "AD1")
    (pin "AD3")
    (pin "AD4")
    (pin "AD6")
    (pin "AD7")
    (pin "AE1")
    (pin "AE2")
    (pin "AE3")
    (pin "AE4")
    (pin "AE5")
    (pin "AE6")
    (pin "N1")
    (pin "P1")
    (pin "P2")
    (pin "P3")
    (pin "P4")
    (pin "P5")
    (pin "R1")
    (pin "R3")
    (pin "R4")
    (pin "R6")
    (pin "R7")
    (pin "T1")
    (pin "T2")
    (pin "T3")
    (pin "T4")
    (pin "T5")
    (pin "T6")
    (pin "T7")
    (pin "U1")
    (pin "U10")
    (pin "U2")
    (pin "U3")
    (pin "U4")
    (pin "U5")
    (pin "U6")
    (pin "U7")
    (pin "V1")
    (pin "V10")
    (pin "V4")
    (pin "V6")
    (pin "V7")
    (pin "W1")
    (pin "W10")
    (pin "W2")
    (pin "W3")
    (pin "W4")
    (pin "W5")
    (pin "Y1")
    (pin "Y3")
    (pin "Y4")
    (pin "Y5")
    (pin "Y6")
    (pin "Y7")
    (pin "B1")
    (pin "C1")
    (pin "C2")
    (pin "C3")
    (pin "C4")
    (pin "C5")
    (pin "D1")
    (pin "D2")
    (pin "D3")
    (pin "D4")
    (pin "D5")
    (pin "E1")
    (pin "E3")
    (pin "E4")
    (pin "F1")
    (pin "F2")
    (pin "F3")
    (pin "F4")
    (pin "F5")
    (pin "H1")
    (pin "H2")
    (pin "H3")
    (pin "H5")
    (pin "H6")
    (pin "J1")
    (pin "J3")
    (pin "J4")
    (pin "J6")
    (pin "J7")
    (pin "K1")
    (pin "K2")
    (pin "K3")
    (pin "K4")
    (pin "K5")
    (pin "K6")
    (pin "K7")
    (pin "L1")
    (pin "L2")
    (pin "L3")
    (pin "L4")
    (pin "L6")
    (pin "L7")
    (pin "M10")
    (pin "N3")
    (pin "N4")
    (pin "N6")
    (pin "N7")
    (pin "P10")
    (pin "P6")
    (pin "P7")
    (pin "R10")
    (pin "T10")
    (pin "AB10")
    (pin "AC10")
    (pin "AG1")
    (pin "AG3")
    (pin "AG4")
    (pin "AH1")
    (pin "AH3")
    (pin "AH4")
    (pin "AJ1")
    (pin "AJ2")
    (pin "AJ3")
    (pin "AJ4")
    (pin "AK1")
    (pin "AK2")
    (pin "AK3")
    (pin "AK4")
    (pin "AL1")
    (pin "AL3")
    (pin "AL4")
    (pin "AM2")
    (pin "AM3")
    (pin "AM4")
    (pin "AG5")
    (pin "AJ5")
    (pin "AK5")
    (pin "AM5")
    (pin "AK10")
    (pin "AK12")
    (pin "AK13")
    (pin "AK9")
    (pin "AM11")
    (pin "AM12")
    (pin "AM14")
    (pin "AM15")
    (pin "AM8")
    (pin "AM9")
    (pin "AK18")
    (pin "AK19")
    (pin "AK21")
    (pin "AK22")
    (pin "AM17")
    (pin "AM18")
    (pin "AM20")
    (pin "AM21")
    (pin "AM23")
    (pin "AM24")
    (instances
      (project "ecp5-dc-scm"
        (path ""
          (reference "U21") (unit 6)
        )
      )
    )
  )

  (symbol (lib_id "antmicropower:GND") (at 26.67 40.64 0) (unit 1)
    (in_bom yes) (on_board yes) (dnp no)
    (property "Reference" "#PWR0125" (at 26.67 46.99 0)
      (effects (font (size 1.27 1.27)) hide)
    )
    (property "Value" "GND" (at 26.797 45.0342 0)
      (effects (font (size 1.27 1.27)))
    )
    (property "Footprint" "" (at 26.67 40.64 0)
      (effects (font (size 1.27 1.27)) hide)
    )
    (property "Datasheet" "" (at 26.67 40.64 0)
      (effects (font (size 1.27 1.27)) hide)
    )
    (property "Author" "Antmicro" (at 35.56 48.26 0)
      (effects (font (size 1.27 1.27) (thickness 0.15)) (justify left bottom) hide)
    )
    (property "License" "Apache-2.0" (at 35.56 50.8 0)
      (effects (font (size 1.27 1.27) (thickness 0.15)) (justify left bottom) hide)
    )
    (pin "1")
    (instances
      (project "ecp5-dc-scm"
        (path ""
          (reference "#PWR0125") (unit 1)
        )
      )
    )
  )

  (symbol (lib_id "antmicropower:GND") (at 370.84 240.03 0) (unit 1)
    (in_bom yes) (on_board yes) (dnp no)
    (property "Reference" "#PWR0126" (at 370.84 246.38 0)
      (effects (font (size 1.27 1.27)) hide)
    )
    (property "Value" "GND" (at 370.967 244.4242 0)
      (effects (font (size 1.27 1.27)))
    )
    (property "Footprint" "" (at 370.84 240.03 0)
      (effects (font (size 1.27 1.27)) hide)
    )
    (property "Datasheet" "" (at 370.84 240.03 0)
      (effects (font (size 1.27 1.27)) hide)
    )
    (property "Author" "Antmicro" (at 379.73 247.65 0)
      (effects (font (size 1.27 1.27) (thickness 0.15)) (justify left bottom) hide)
    )
    (property "License" "Apache-2.0" (at 379.73 250.19 0)
      (effects (font (size 1.27 1.27) (thickness 0.15)) (justify left bottom) hide)
    )
    (pin "1")
    (instances
      (project "ecp5-dc-scm"
        (path ""
          (reference "#PWR0126") (unit 1)
        )
      )
    )
  )

  (symbol (lib_id "antmicroCapacitors0402:C_100n_0402") (at 346.71 237.49 90) (unit 1)
    (in_bom yes) (on_board yes) (dnp no) (fields_autoplaced)
    (property "Reference" "C241" (at 349.25 233.6736 90)
      (effects (font (size 1.524 1.524)) (justify right))
    )
    (property "Value" "C_100n_0402" (at 350.52 237.49 0)
      (effects (font (size 1.524 1.524)) hide)
    )
    (property "Footprint" "antmicro-footprints:C_0402_1005Metric" (at 341.63 232.41 0)
      (effects (font (size 1.524 1.524)) (justify left) hide)
    )
    (property "Datasheet" "https://www.murata.com/products/productdetail?partno=GRM155R61H104KE14%23" (at 346.71 237.49 0)
      (effects (font (size 1.27 1.27)) hide)
    )
    (property "Manufacturer" "Murata" (at 336.55 232.41 0)
      (effects (font (size 1.524 1.524)) (justify left) hide)
    )
    (property "MPN" "GRM155R61H104KE14D" (at 339.09 232.41 0)
      (effects (font (size 1.524 1.524)) (justify left) hide)
    )
    (property "Val" "100n" (at 349.25 236.2136 90)
      (effects (font (size 1.27 1.27)) (justify right))
    )
    (property "License" "Apache-2.0" (at 369.57 217.17 0)
      (effects (font (size 1.27 1.27) (thickness 0.15)) (justify left bottom) hide)
    )
    (property "Author" "Antmicro" (at 372.11 217.17 0)
      (effects (font (size 1.27 1.27) (thickness 0.15)) (justify left bottom) hide)
    )
    (property "Voltage" "50V" (at 374.65 217.17 0)
      (effects (font (size 1.27 1.27)) (justify left bottom) hide)
    )
    (property "Dielectric" "X5R" (at 377.19 217.17 0)
      (effects (font (size 1.27 1.27)) (justify left bottom) hide)
    )
    (property "Public" "False" (at 379.73 217.17 0)
      (effects (font (size 1.27 1.27)) (justify left bottom) hide)
    )
    (pin "1")
    (pin "2")
    (instances
      (project "ecp5-dc-scm"
        (path ""
          (reference "C241") (unit 1)
        )
      )
    )
  )

  (symbol (lib_id "antmicropower:GND") (at 346.71 238.76 0) (unit 1)
    (in_bom yes) (on_board yes) (dnp no)
    (property "Reference" "#PWR0127" (at 346.71 245.11 0)
      (effects (font (size 1.27 1.27)) hide)
    )
    (property "Value" "GND" (at 346.837 243.1542 0)
      (effects (font (size 1.27 1.27)))
    )
    (property "Footprint" "" (at 346.71 238.76 0)
      (effects (font (size 1.27 1.27)) hide)
    )
    (property "Datasheet" "" (at 346.71 238.76 0)
      (effects (font (size 1.27 1.27)) hide)
    )
    (property "Author" "Antmicro" (at 355.6 246.38 0)
      (effects (font (size 1.27 1.27) (thickness 0.15)) (justify left bottom) hide)
    )
    (property "License" "Apache-2.0" (at 355.6 248.92 0)
      (effects (font (size 1.27 1.27) (thickness 0.15)) (justify left bottom) hide)
    )
    (pin "1")
    (instances
      (project "ecp5-dc-scm"
        (path ""
          (reference "#PWR0127") (unit 1)
        )
      )
    )
  )

  (symbol (lib_id "antmicroCapacitors0402:C_100n_0402") (at 204.47 257.81 0) (mirror x) (unit 1)
    (in_bom yes) (on_board yes) (dnp no) (fields_autoplaced)
    (property "Reference" "C57" (at 207.0163 261.62 0)
      (effects (font (size 1.524 1.524)))
    )
    (property "Value" "C_100n_0402" (at 204.47 254 0)
      (effects (font (size 1.524 1.524)) hide)
    )
    (property "Footprint" "antmicro-footprints:C_0402_1005Metric" (at 209.55 262.89 0)
      (effects (font (size 1.524 1.524)) (justify left) hide)
    )
    (property "Datasheet" "https://www.murata.com/products/productdetail?partno=GRM155R61H104KE14%23" (at 204.47 257.81 0)
      (effects (font (size 1.27 1.27)) hide)
    )
    (property "Manufacturer" "Murata" (at 209.55 267.97 0)
      (effects (font (size 1.524 1.524)) (justify left) hide)
    )
    (property "MPN" "GRM155R61H104KE14D" (at 209.55 265.43 0)
      (effects (font (size 1.524 1.524)) (justify left) hide)
    )
    (property "Val" "100n" (at 207.0163 264.16 0)
      (effects (font (size 1.27 1.27)))
    )
    (property "License" "Apache-2.0" (at 224.79 234.95 0)
      (effects (font (size 1.27 1.27) (thickness 0.15)) (justify left bottom) hide)
    )
    (property "Author" "Antmicro" (at 224.79 232.41 0)
      (effects (font (size 1.27 1.27) (thickness 0.15)) (justify left bottom) hide)
    )
    (property "Voltage" "50V" (at 224.79 229.87 0)
      (effects (font (size 1.27 1.27)) (justify left bottom) hide)
    )
    (property "Dielectric" "X5R" (at 224.79 227.33 0)
      (effects (font (size 1.27 1.27)) (justify left bottom) hide)
    )
    (property "Public" "False" (at 224.79 224.79 0)
      (effects (font (size 1.27 1.27)) (justify left bottom) hide)
    )
    (pin "1")
    (pin "2")
    (instances
      (project "ecp5-dc-scm"
        (path ""
          (reference "C57") (unit 1)
        )
      )
    )
  )

  (symbol (lib_id "antmicroCapacitors0402:C_100n_0402") (at 208.28 255.27 0) (mirror x) (unit 1)
    (in_bom yes) (on_board yes) (dnp no) (fields_autoplaced)
    (property "Reference" "C58" (at 210.8263 248.92 0)
      (effects (font (size 1.524 1.524)))
    )
    (property "Value" "C_100n_0402" (at 208.28 251.46 0)
      (effects (font (size 1.524 1.524)) hide)
    )
    (property "Footprint" "antmicro-footprints:C_0402_1005Metric" (at 213.36 260.35 0)
      (effects (font (size 1.524 1.524)) (justify left) hide)
    )
    (property "Datasheet" "https://www.murata.com/products/productdetail?partno=GRM155R61H104KE14%23" (at 208.28 255.27 0)
      (effects (font (size 1.27 1.27)) hide)
    )
    (property "Manufacturer" "Murata" (at 213.36 265.43 0)
      (effects (font (size 1.524 1.524)) (justify left) hide)
    )
    (property "MPN" "GRM155R61H104KE14D" (at 213.36 262.89 0)
      (effects (font (size 1.524 1.524)) (justify left) hide)
    )
    (property "Val" "100n" (at 210.8263 251.46 0)
      (effects (font (size 1.27 1.27)))
    )
    (property "License" "Apache-2.0" (at 228.6 232.41 0)
      (effects (font (size 1.27 1.27) (thickness 0.15)) (justify left bottom) hide)
    )
    (property "Author" "Antmicro" (at 228.6 229.87 0)
      (effects (font (size 1.27 1.27) (thickness 0.15)) (justify left bottom) hide)
    )
    (property "Voltage" "50V" (at 228.6 227.33 0)
      (effects (font (size 1.27 1.27)) (justify left bottom) hide)
    )
    (property "Dielectric" "X5R" (at 228.6 224.79 0)
      (effects (font (size 1.27 1.27)) (justify left bottom) hide)
    )
    (property "Public" "False" (at 228.6 222.25 0)
      (effects (font (size 1.27 1.27)) (justify left bottom) hide)
    )
    (pin "1")
    (pin "2")
    (instances
      (project "ecp5-dc-scm"
        (path ""
          (reference "C58") (unit 1)
        )
      )
    )
  )

  (symbol (lib_id "antmicroCapacitors0402:C_100n_0402") (at 278.13 99.06 270) (mirror x) (unit 1)
    (in_bom yes) (on_board yes) (dnp no)
    (property "Reference" "C216" (at 278.13 94.615 90)
      (effects (font (size 1.524 1.524)) (justify left))
    )
    (property "Value" "C_100n_0402" (at 274.32 99.06 0)
      (effects (font (size 1.524 1.524)) hide)
    )
    (property "Footprint" "antmicro-footprints:C_0402_1005Metric" (at 283.21 93.98 0)
      (effects (font (size 1.524 1.524)) (justify left) hide)
    )
    (property "Datasheet" "https://www.murata.com/products/productdetail?partno=GRM155R61H104KE14%23" (at 278.13 99.06 0)
      (effects (font (size 1.27 1.27)) hide)
    )
    (property "Manufacturer" "Murata" (at 288.29 93.98 0)
      (effects (font (size 1.524 1.524)) (justify left) hide)
    )
    (property "MPN" "GRM155R61H104KE14D" (at 285.75 93.98 0)
      (effects (font (size 1.524 1.524)) (justify left) hide)
    )
    (property "Val" "100n" (at 278.13 98.425 90)
      (effects (font (size 1.27 1.27)) (justify left))
    )
    (property "License" "Apache-2.0" (at 255.27 78.74 0)
      (effects (font (size 1.27 1.27) (thickness 0.15)) (justify left bottom) hide)
    )
    (property "Author" "Antmicro" (at 252.73 78.74 0)
      (effects (font (size 1.27 1.27) (thickness 0.15)) (justify left bottom) hide)
    )
    (property "Voltage" "50V" (at 250.19 78.74 0)
      (effects (font (size 1.27 1.27)) (justify left bottom) hide)
    )
    (property "Dielectric" "X5R" (at 247.65 78.74 0)
      (effects (font (size 1.27 1.27)) (justify left bottom) hide)
    )
    (property "Public" "False" (at 245.11 78.74 0)
      (effects (font (size 1.27 1.27)) (justify left bottom) hide)
    )
    (pin "1")
    (pin "2")
    (instances
      (project "ecp5-dc-scm"
        (path ""
          (reference "C216") (unit 1)
        )
      )
    )
  )

  (symbol (lib_id "antmicroCapacitors0402:C_100n_0402") (at 273.05 99.06 90) (unit 1)
    (in_bom yes) (on_board yes) (dnp no)
    (property "Reference" "C217" (at 272.415 94.615 90)
      (effects (font (size 1.524 1.524)) (justify left))
    )
    (property "Value" "C_100n_0402" (at 276.86 99.06 0)
      (effects (font (size 1.524 1.524)) hide)
    )
    (property "Footprint" "antmicro-footprints:C_0402_1005Metric" (at 267.97 93.98 0)
      (effects (font (size 1.524 1.524)) (justify left) hide)
    )
    (property "Datasheet" "https://www.murata.com/products/productdetail?partno=GRM155R61H104KE14%23" (at 273.05 99.06 0)
      (effects (font (size 1.27 1.27)) hide)
    )
    (property "Manufacturer" "Murata" (at 262.89 93.98 0)
      (effects (font (size 1.524 1.524)) (justify left) hide)
    )
    (property "MPN" "GRM155R61H104KE14D" (at 265.43 93.98 0)
      (effects (font (size 1.524 1.524)) (justify left) hide)
    )
    (property "Val" "100n" (at 272.415 98.425 90)
      (effects (font (size 1.27 1.27)) (justify left))
    )
    (property "License" "Apache-2.0" (at 295.91 78.74 0)
      (effects (font (size 1.27 1.27) (thickness 0.15)) (justify left bottom) hide)
    )
    (property "Author" "Antmicro" (at 298.45 78.74 0)
      (effects (font (size 1.27 1.27) (thickness 0.15)) (justify left bottom) hide)
    )
    (property "Voltage" "50V" (at 300.99 78.74 0)
      (effects (font (size 1.27 1.27)) (justify left bottom) hide)
    )
    (property "Dielectric" "X5R" (at 303.53 78.74 0)
      (effects (font (size 1.27 1.27)) (justify left bottom) hide)
    )
    (property "Public" "False" (at 306.07 78.74 0)
      (effects (font (size 1.27 1.27)) (justify left bottom) hide)
    )
    (pin "1")
    (pin "2")
    (instances
      (project "ecp5-dc-scm"
        (path ""
          (reference "C217") (unit 1)
        )
      )
    )
  )

  (symbol (lib_id "antmicropower:GND") (at 278.13 100.33 0) (unit 1)
    (in_bom yes) (on_board yes) (dnp no)
    (property "Reference" "#PWR0130" (at 278.13 106.68 0)
      (effects (font (size 1.27 1.27)) hide)
    )
    (property "Value" "GND" (at 278.257 104.7242 0)
      (effects (font (size 1.27 1.27)))
    )
    (property "Footprint" "" (at 278.13 100.33 0)
      (effects (font (size 1.27 1.27)) hide)
    )
    (property "Datasheet" "" (at 278.13 100.33 0)
      (effects (font (size 1.27 1.27)) hide)
    )
    (property "Author" "Antmicro" (at 287.02 107.95 0)
      (effects (font (size 1.27 1.27) (thickness 0.15)) (justify left bottom) hide)
    )
    (property "License" "Apache-2.0" (at 287.02 110.49 0)
      (effects (font (size 1.27 1.27) (thickness 0.15)) (justify left bottom) hide)
    )
    (pin "1")
    (instances
      (project "ecp5-dc-scm"
        (path ""
          (reference "#PWR0130") (unit 1)
        )
      )
    )
  )

  (symbol (lib_id "antmicroFPGAChips:ECP5_LFE5UM5G-85") (at 151.13 218.44 0) (unit 9)
    (in_bom yes) (on_board yes) (dnp no) (fields_autoplaced)
    (property "Reference" "U21" (at 163.83 210.82 0)
      (effects (font (size 1.524 1.524)))
    )
    (property "Value" "ECP5UM5G_85_CABGA756" (at 163.83 213.36 0)
      (effects (font (size 1.524 1.524)))
    )
    (property "Footprint" "antmicro-footprints:BGA-1024-756_27x27mm_Layout32x32_P0.8mm" (at 151.13 218.44 0)
      (effects (font (size 1.27 1.27)) hide)
    )
    (property "Datasheet" "https://www.latticesemi.com/-/media/LatticeSemi/Documents/DataSheets/ECP5/FPGA-DS-02012-2-2-ECP5-ECP5G-Family-Data-Sheet.ashx?document_id=50461" (at 151.13 218.44 0)
      (effects (font (size 1.27 1.27)) hide)
    )
    (property "MPN" "LFE5UM5G-85F-8BG756C" (at 154.94 219.71 0)
      (effects (font (size 1.524 1.524)) (justify right) hide)
    )
    (property "Manufacturer" "Lattice Semiconductor" (at 177.292 237.4646 0)
      (effects (font (size 1.27 1.27)) (justify left) hide)
    )
    (property "Author" "Antmicro" (at 228.6 237.49 0)
      (effects (font (size 1.27 1.27) (thickness 0.15)) (justify left bottom) hide)
    )
    (property "License" "Apache-2.0" (at 228.6 240.03 0)
      (effects (font (size 1.27 1.27) (thickness 0.15)) (justify left bottom) hide)
    )
    (pin "AA11")
    (pin "AA12")
    (pin "AA13")
    (pin "AA14")
    (pin "AA15")
    (pin "AA16")
    (pin "AA17")
    (pin "AA18")
    (pin "AA19")
    (pin "AA20")
    (pin "AA21")
    (pin "AA22")
    (pin "AB11")
    (pin "AB12")
    (pin "AB13")
    (pin "AB14")
    (pin "AB15")
    (pin "AB16")
    (pin "AB17")
    (pin "AB18")
    (pin "AB19")
    (pin "AB20")
    (pin "AB21")
    (pin "AB22")
    (pin "AC11")
    (pin "AC12")
    (pin "AC13")
    (pin "AC14")
    (pin "AC15")
    (pin "AC16")
    (pin "AC17")
    (pin "AC18")
    (pin "AC19")
    (pin "AC20")
    (pin "AC21")
    (pin "AC22")
    (pin "AC29")
    (pin "AC4")
    (pin "AD2")
    (pin "AD28")
    (pin "AD31")
    (pin "AD5")
    (pin "AE26")
    (pin "AE7")
    (pin "AF11")
    (pin "AF12")
    (pin "AF14")
    (pin "AF15")
    (pin "AF16")
    (pin "AF17")
    (pin "AF19")
    (pin "AF20")
    (pin "AF22")
    (pin "AF23")
    (pin "AG11")
    (pin "AG12")
    (pin "AG14")
    (pin "AG15")
    (pin "AG16")
    (pin "AG17")
    (pin "AG19")
    (pin "AG2")
    (pin "AG20")
    (pin "AG22")
    (pin "AG23")
    (pin "AG24")
    (pin "AG31")
    (pin "AG9")
    (pin "AH11")
    (pin "AH12")
    (pin "AH14")
    (pin "AH15")
    (pin "AH16")
    (pin "AH17")
    (pin "AH19")
    (pin "AH2")
    (pin "AH20")
    (pin "AH22")
    (pin "AH23")
    (pin "AH24")
    (pin "AH25")
    (pin "AH26")
    (pin "AH29")
    (pin "AH31")
    (pin "AH5")
    (pin "AH7")
    (pin "AH8")
    (pin "AH9")
    (pin "AJ10")
    (pin "AJ11")
    (pin "AJ12")
    (pin "AJ13")
    (pin "AJ14")
    (pin "AJ15")
    (pin "AJ16")
    (pin "AJ17")
    (pin "AJ18")
    (pin "AJ19")
    (pin "AJ20")
    (pin "AJ21")
    (pin "AJ22")
    (pin "AJ23")
    (pin "AJ24")
    (pin "AJ25")
    (pin "AJ26")
    (pin "AJ7")
    (pin "AJ8")
    (pin "AJ9")
    (pin "AK11")
    (pin "AK14")
    (pin "AK15")
    (pin "AK16")
    (pin "AK17")
    (pin "AK20")
    (pin "AK23")
    (pin "AK24")
    (pin "AK25")
    (pin "AK26")
    (pin "AK7")
    (pin "AK8")
    (pin "AL11")
    (pin "AL12")
    (pin "AL14")
    (pin "AL15")
    (pin "AL17")
    (pin "AL18")
    (pin "AL2")
    (pin "AL20")
    (pin "AL21")
    (pin "AL23")
    (pin "AL24")
    (pin "AL26")
    (pin "AL29")
    (pin "AL31")
    (pin "AL5")
    (pin "AL7")
    (pin "AL8")
    (pin "AL9")
    (pin "AM26")
    (pin "AM7")
    (pin "B13")
    (pin "B15")
    (pin "B18")
    (pin "B2")
    (pin "B20")
    (pin "B24")
    (pin "B28")
    (pin "B31")
    (pin "B5")
    (pin "B9")
    (pin "E13")
    (pin "E15")
    (pin "E18")
    (pin "E2")
    (pin "E20")
    (pin "E24")
    (pin "E26")
    (pin "E28")
    (pin "E31")
    (pin "E5")
    (pin "E7")
    (pin "E9")
    (pin "G10")
    (pin "G11")
    (pin "G14")
    (pin "G15")
    (pin "G16")
    (pin "G17")
    (pin "G18")
    (pin "G19")
    (pin "G22")
    (pin "G23")
    (pin "G24")
    (pin "G9")
    (pin "H29")
    (pin "H4")
    (pin "J2")
    (pin "J28")
    (pin "J31")
    (pin "J5")
    (pin "K10")
    (pin "K11")
    (pin "K13")
    (pin "K20")
    (pin "K22")
    (pin "K23")
    (pin "L10")
    (pin "L11")
    (pin "L12")
    (pin "L13")
    (pin "L14")
    (pin "L15")
    (pin "L16")
    (pin "L17")
    (pin "L18")
    (pin "L19")
    (pin "L20")
    (pin "L21")
    (pin "L22")
    (pin "L23")
    (pin "L28")
    (pin "L5")
    (pin "M11")
    (pin "M12")
    (pin "M13")
    (pin "M14")
    (pin "M15")
    (pin "M16")
    (pin "M17")
    (pin "M18")
    (pin "M19")
    (pin "M20")
    (pin "M21")
    (pin "M22")
    (pin "N10")
    (pin "N11")
    (pin "N12")
    (pin "N13")
    (pin "N14")
    (pin "N15")
    (pin "N16")
    (pin "N17")
    (pin "N18")
    (pin "N19")
    (pin "N2")
    (pin "N20")
    (pin "N21")
    (pin "N22")
    (pin "N23")
    (pin "N28")
    (pin "N31")
    (pin "N5")
    (pin "P11")
    (pin "P12")
    (pin "P13")
    (pin "P14")
    (pin "P15")
    (pin "P16")
    (pin "P17")
    (pin "P18")
    (pin "P19")
    (pin "P20")
    (pin "P21")
    (pin "P22")
    (pin "R11")
    (pin "R12")
    (pin "R13")
    (pin "R14")
    (pin "R15")
    (pin "R16")
    (pin "R17")
    (pin "R18")
    (pin "R19")
    (pin "R2")
    (pin "R20")
    (pin "R21")
    (pin "R22")
    (pin "R28")
    (pin "R31")
    (pin "R5")
    (pin "T11")
    (pin "T12")
    (pin "T13")
    (pin "T14")
    (pin "T15")
    (pin "T16")
    (pin "T17")
    (pin "T18")
    (pin "T19")
    (pin "T20")
    (pin "T21")
    (pin "T22")
    (pin "U11")
    (pin "U12")
    (pin "U13")
    (pin "U14")
    (pin "U15")
    (pin "U16")
    (pin "U17")
    (pin "U18")
    (pin "U19")
    (pin "U20")
    (pin "U21")
    (pin "U22")
    (pin "V11")
    (pin "V12")
    (pin "V13")
    (pin "V14")
    (pin "V15")
    (pin "V16")
    (pin "V17")
    (pin "V18")
    (pin "V19")
    (pin "V2")
    (pin "V20")
    (pin "V21")
    (pin "V22")
    (pin "V28")
    (pin "V3")
    (pin "V30")
    (pin "V31")
    (pin "V5")
    (pin "W11")
    (pin "W12")
    (pin "W13")
    (pin "W14")
    (pin "W15")
    (pin "W16")
    (pin "W17")
    (pin "W18")
    (pin "W19")
    (pin "W20")
    (pin "W21")
    (pin "W22")
    (pin "W27")
    (pin "W6")
    (pin "Y10")
    (pin "Y11")
    (pin "Y12")
    (pin "Y13")
    (pin "Y14")
    (pin "Y15")
    (pin "Y16")
    (pin "Y17")
    (pin "Y18")
    (pin "Y19")
    (pin "Y2")
    (pin "Y20")
    (pin "Y21")
    (pin "Y22")
    (pin "Y23")
    (pin "Y31")
    (pin "A10")
    (pin "A11")
    (pin "A13")
    (pin "A14")
    (pin "A15")
    (pin "A16")
    (pin "A17")
    (pin "A2")
    (pin "A3")
    (pin "A4")
    (pin "A5")
    (pin "A7")
    (pin "A8")
    (pin "A9")
    (pin "B10")
    (pin "B11")
    (pin "B14")
    (pin "B16")
    (pin "B17")
    (pin "B3")
    (pin "B4")
    (pin "B7")
    (pin "B8")
    (pin "C10")
    (pin "C11")
    (pin "C13")
    (pin "C14")
    (pin "C15")
    (pin "C16")
    (pin "C17")
    (pin "C7")
    (pin "C8")
    (pin "C9")
    (pin "D10")
    (pin "D11")
    (pin "D13")
    (pin "D14")
    (pin "D15")
    (pin "D16")
    (pin "D17")
    (pin "D7")
    (pin "D8")
    (pin "D9")
    (pin "E10")
    (pin "E11")
    (pin "E14")
    (pin "E16")
    (pin "E8")
    (pin "F10")
    (pin "F11")
    (pin "F13")
    (pin "F14")
    (pin "F15")
    (pin "F16")
    (pin "F8")
    (pin "F9")
    (pin "K12")
    (pin "K14")
    (pin "K15")
    (pin "K16")
    (pin "A18")
    (pin "A19")
    (pin "A20")
    (pin "A22")
    (pin "A23")
    (pin "A24")
    (pin "A25")
    (pin "A26")
    (pin "A28")
    (pin "A29")
    (pin "A30")
    (pin "A31")
    (pin "B19")
    (pin "B22")
    (pin "B23")
    (pin "B25")
    (pin "B26")
    (pin "B29")
    (pin "B30")
    (pin "C18")
    (pin "C19")
    (pin "C20")
    (pin "C22")
    (pin "C23")
    (pin "C24")
    (pin "C25")
    (pin "C26")
    (pin "D18")
    (pin "D19")
    (pin "D20")
    (pin "D22")
    (pin "D23")
    (pin "D24")
    (pin "D25")
    (pin "D26")
    (pin "E17")
    (pin "E19")
    (pin "E22")
    (pin "E23")
    (pin "E25")
    (pin "F17")
    (pin "F18")
    (pin "F19")
    (pin "F20")
    (pin "F22")
    (pin "F23")
    (pin "F24")
    (pin "F25")
    (pin "K17")
    (pin "K18")
    (pin "K19")
    (pin "K21")
    (pin "B32")
    (pin "C28")
    (pin "C29")
    (pin "C30")
    (pin "C31")
    (pin "C32")
    (pin "D28")
    (pin "D29")
    (pin "D30")
    (pin "D31")
    (pin "D32")
    (pin "E29")
    (pin "E30")
    (pin "E32")
    (pin "F28")
    (pin "F29")
    (pin "F30")
    (pin "F31")
    (pin "F32")
    (pin "H27")
    (pin "H28")
    (pin "H30")
    (pin "H31")
    (pin "H32")
    (pin "J26")
    (pin "J27")
    (pin "J29")
    (pin "J30")
    (pin "J32")
    (pin "K26")
    (pin "K27")
    (pin "K28")
    (pin "K29")
    (pin "K30")
    (pin "K31")
    (pin "K32")
    (pin "L26")
    (pin "L27")
    (pin "L29")
    (pin "L30")
    (pin "L31")
    (pin "L32")
    (pin "M23")
    (pin "N26")
    (pin "N27")
    (pin "N29")
    (pin "N30")
    (pin "P23")
    (pin "P26")
    (pin "P27")
    (pin "R23")
    (pin "T23")
    (pin "AA23")
    (pin "AB26")
    (pin "AB27")
    (pin "AB28")
    (pin "AB29")
    (pin "AB30")
    (pin "AB31")
    (pin "AB32")
    (pin "AC26")
    (pin "AC27")
    (pin "AC28")
    (pin "AC30")
    (pin "AC31")
    (pin "AC32")
    (pin "AD26")
    (pin "AD27")
    (pin "AD29")
    (pin "AD30")
    (pin "AD32")
    (pin "AE27")
    (pin "AE28")
    (pin "AE29")
    (pin "AE30")
    (pin "AE31")
    (pin "AE32")
    (pin "N32")
    (pin "P28")
    (pin "P29")
    (pin "P30")
    (pin "P31")
    (pin "P32")
    (pin "R26")
    (pin "R27")
    (pin "R29")
    (pin "R30")
    (pin "R32")
    (pin "T26")
    (pin "T27")
    (pin "T28")
    (pin "T29")
    (pin "T30")
    (pin "T31")
    (pin "T32")
    (pin "U23")
    (pin "U26")
    (pin "U27")
    (pin "U28")
    (pin "U29")
    (pin "U30")
    (pin "U31")
    (pin "U32")
    (pin "V23")
    (pin "V26")
    (pin "V27")
    (pin "V29")
    (pin "V32")
    (pin "W23")
    (pin "W28")
    (pin "W29")
    (pin "W30")
    (pin "W31")
    (pin "W32")
    (pin "Y26")
    (pin "Y27")
    (pin "Y28")
    (pin "Y29")
    (pin "Y30")
    (pin "Y32")
    (pin "AB23")
    (pin "AC23")
    (pin "AG28")
    (pin "AG29")
    (pin "AG30")
    (pin "AG32")
    (pin "AH28")
    (pin "AH30")
    (pin "AH32")
    (pin "AJ28")
    (pin "AJ29")
    (pin "AJ30")
    (pin "AJ31")
    (pin "AJ32")
    (pin "AK28")
    (pin "AK29")
    (pin "AK30")
    (pin "AK31")
    (pin "AK32")
    (pin "AL28")
    (pin "AL30")
    (pin "AL32")
    (pin "AM28")
    (pin "AM29")
    (pin "AM30")
    (pin "AM31")
    (pin "AA10")
    (pin "AB1")
    (pin "AB2")
    (pin "AB3")
    (pin "AB4")
    (pin "AB5")
    (pin "AB6")
    (pin "AB7")
    (pin "AC1")
    (pin "AC2")
    (pin "AC3")
    (pin "AC5")
    (pin "AC6")
    (pin "AC7")
    (pin "AD1")
    (pin "AD3")
    (pin "AD4")
    (pin "AD6")
    (pin "AD7")
    (pin "AE1")
    (pin "AE2")
    (pin "AE3")
    (pin "AE4")
    (pin "AE5")
    (pin "AE6")
    (pin "N1")
    (pin "P1")
    (pin "P2")
    (pin "P3")
    (pin "P4")
    (pin "P5")
    (pin "R1")
    (pin "R3")
    (pin "R4")
    (pin "R6")
    (pin "R7")
    (pin "T1")
    (pin "T2")
    (pin "T3")
    (pin "T4")
    (pin "T5")
    (pin "T6")
    (pin "T7")
    (pin "U1")
    (pin "U10")
    (pin "U2")
    (pin "U3")
    (pin "U4")
    (pin "U5")
    (pin "U6")
    (pin "U7")
    (pin "V1")
    (pin "V10")
    (pin "V4")
    (pin "V6")
    (pin "V7")
    (pin "W1")
    (pin "W10")
    (pin "W2")
    (pin "W3")
    (pin "W4")
    (pin "W5")
    (pin "Y1")
    (pin "Y3")
    (pin "Y4")
    (pin "Y5")
    (pin "Y6")
    (pin "Y7")
    (pin "B1")
    (pin "C1")
    (pin "C2")
    (pin "C3")
    (pin "C4")
    (pin "C5")
    (pin "D1")
    (pin "D2")
    (pin "D3")
    (pin "D4")
    (pin "D5")
    (pin "E1")
    (pin "E3")
    (pin "E4")
    (pin "F1")
    (pin "F2")
    (pin "F3")
    (pin "F4")
    (pin "F5")
    (pin "H1")
    (pin "H2")
    (pin "H3")
    (pin "H5")
    (pin "H6")
    (pin "J1")
    (pin "J3")
    (pin "J4")
    (pin "J6")
    (pin "J7")
    (pin "K1")
    (pin "K2")
    (pin "K3")
    (pin "K4")
    (pin "K5")
    (pin "K6")
    (pin "K7")
    (pin "L1")
    (pin "L2")
    (pin "L3")
    (pin "L4")
    (pin "L6")
    (pin "L7")
    (pin "M10")
    (pin "N3")
    (pin "N4")
    (pin "N6")
    (pin "N7")
    (pin "P10")
    (pin "P6")
    (pin "P7")
    (pin "R10")
    (pin "T10")
    (pin "AB10")
    (pin "AC10")
    (pin "AG1")
    (pin "AG3")
    (pin "AG4")
    (pin "AH1")
    (pin "AH3")
    (pin "AH4")
    (pin "AJ1")
    (pin "AJ2")
    (pin "AJ3")
    (pin "AJ4")
    (pin "AK1")
    (pin "AK2")
    (pin "AK3")
    (pin "AK4")
    (pin "AL1")
    (pin "AL3")
    (pin "AL4")
    (pin "AM2")
    (pin "AM3")
    (pin "AM4")
    (pin "AG5")
    (pin "AJ5")
    (pin "AK5")
    (pin "AM5")
    (pin "AK10")
    (pin "AK12")
    (pin "AK13")
    (pin "AK9")
    (pin "AM11")
    (pin "AM12")
    (pin "AM14")
    (pin "AM15")
    (pin "AM8")
    (pin "AM9")
    (pin "AK18")
    (pin "AK19")
    (pin "AK21")
    (pin "AK22")
    (pin "AM17")
    (pin "AM18")
    (pin "AM20")
    (pin "AM21")
    (pin "AM23")
    (pin "AM24")
    (instances
      (project "ecp5-dc-scm"
        (path ""
          (reference "U21") (unit 9)
        )
      )
    )
  )

  (symbol (lib_id "antmicroFPGAChips:ECP5_LFE5UM5G-85") (at 367.03 55.88 0) (unit 8)
    (in_bom yes) (on_board yes) (dnp no)
    (property "Reference" "U21" (at 372.11 41.91 0)
      (effects (font (size 1.524 1.524)) (justify left))
    )
    (property "Value" "ECP5UM5G_85_CABGA756" (at 372.11 180.34 0)
      (effects (font (size 1.524 1.524)) (justify left))
    )
    (property "Footprint" "antmicro-footprints:BGA-1024-756_27x27mm_Layout32x32_P0.8mm" (at 367.03 55.88 0)
      (effects (font (size 1.27 1.27)) hide)
    )
    (property "Datasheet" "https://www.latticesemi.com/-/media/LatticeSemi/Documents/DataSheets/ECP5/FPGA-DS-02012-2-2-ECP5-ECP5G-Family-Data-Sheet.ashx?document_id=50461" (at 367.03 55.88 0)
      (effects (font (size 1.27 1.27)) hide)
    )
    (property "MPN" "LFE5UM5G-85F-8BG756C" (at 370.84 57.15 0)
      (effects (font (size 1.524 1.524)) (justify right) hide)
    )
    (property "Manufacturer" "Lattice Semiconductor" (at 395.732 110.4646 0)
      (effects (font (size 1.27 1.27)) (justify left) hide)
    )
    (property "Author" "Antmicro" (at 444.5 74.93 0)
      (effects (font (size 1.27 1.27) (thickness 0.15)) (justify left bottom) hide)
    )
    (property "License" "Apache-2.0" (at 444.5 77.47 0)
      (effects (font (size 1.27 1.27) (thickness 0.15)) (justify left bottom) hide)
    )
    (pin "AA11")
    (pin "AA12")
    (pin "AA13")
    (pin "AA14")
    (pin "AA15")
    (pin "AA16")
    (pin "AA17")
    (pin "AA18")
    (pin "AA19")
    (pin "AA20")
    (pin "AA21")
    (pin "AA22")
    (pin "AB11")
    (pin "AB12")
    (pin "AB13")
    (pin "AB14")
    (pin "AB15")
    (pin "AB16")
    (pin "AB17")
    (pin "AB18")
    (pin "AB19")
    (pin "AB20")
    (pin "AB21")
    (pin "AB22")
    (pin "AC11")
    (pin "AC12")
    (pin "AC13")
    (pin "AC14")
    (pin "AC15")
    (pin "AC16")
    (pin "AC17")
    (pin "AC18")
    (pin "AC19")
    (pin "AC20")
    (pin "AC21")
    (pin "AC22")
    (pin "AC29")
    (pin "AC4")
    (pin "AD2")
    (pin "AD28")
    (pin "AD31")
    (pin "AD5")
    (pin "AE26")
    (pin "AE7")
    (pin "AF11")
    (pin "AF12")
    (pin "AF14")
    (pin "AF15")
    (pin "AF16")
    (pin "AF17")
    (pin "AF19")
    (pin "AF20")
    (pin "AF22")
    (pin "AF23")
    (pin "AG11")
    (pin "AG12")
    (pin "AG14")
    (pin "AG15")
    (pin "AG16")
    (pin "AG17")
    (pin "AG19")
    (pin "AG2")
    (pin "AG20")
    (pin "AG22")
    (pin "AG23")
    (pin "AG24")
    (pin "AG31")
    (pin "AG9")
    (pin "AH11")
    (pin "AH12")
    (pin "AH14")
    (pin "AH15")
    (pin "AH16")
    (pin "AH17")
    (pin "AH19")
    (pin "AH2")
    (pin "AH20")
    (pin "AH22")
    (pin "AH23")
    (pin "AH24")
    (pin "AH25")
    (pin "AH26")
    (pin "AH29")
    (pin "AH31")
    (pin "AH5")
    (pin "AH7")
    (pin "AH8")
    (pin "AH9")
    (pin "AJ10")
    (pin "AJ11")
    (pin "AJ12")
    (pin "AJ13")
    (pin "AJ14")
    (pin "AJ15")
    (pin "AJ16")
    (pin "AJ17")
    (pin "AJ18")
    (pin "AJ19")
    (pin "AJ20")
    (pin "AJ21")
    (pin "AJ22")
    (pin "AJ23")
    (pin "AJ24")
    (pin "AJ25")
    (pin "AJ26")
    (pin "AJ7")
    (pin "AJ8")
    (pin "AJ9")
    (pin "AK11")
    (pin "AK14")
    (pin "AK15")
    (pin "AK16")
    (pin "AK17")
    (pin "AK20")
    (pin "AK23")
    (pin "AK24")
    (pin "AK25")
    (pin "AK26")
    (pin "AK7")
    (pin "AK8")
    (pin "AL11")
    (pin "AL12")
    (pin "AL14")
    (pin "AL15")
    (pin "AL17")
    (pin "AL18")
    (pin "AL2")
    (pin "AL20")
    (pin "AL21")
    (pin "AL23")
    (pin "AL24")
    (pin "AL26")
    (pin "AL29")
    (pin "AL31")
    (pin "AL5")
    (pin "AL7")
    (pin "AL8")
    (pin "AL9")
    (pin "AM26")
    (pin "AM7")
    (pin "B13")
    (pin "B15")
    (pin "B18")
    (pin "B2")
    (pin "B20")
    (pin "B24")
    (pin "B28")
    (pin "B31")
    (pin "B5")
    (pin "B9")
    (pin "E13")
    (pin "E15")
    (pin "E18")
    (pin "E2")
    (pin "E20")
    (pin "E24")
    (pin "E26")
    (pin "E28")
    (pin "E31")
    (pin "E5")
    (pin "E7")
    (pin "E9")
    (pin "G10")
    (pin "G11")
    (pin "G14")
    (pin "G15")
    (pin "G16")
    (pin "G17")
    (pin "G18")
    (pin "G19")
    (pin "G22")
    (pin "G23")
    (pin "G24")
    (pin "G9")
    (pin "H29")
    (pin "H4")
    (pin "J2")
    (pin "J28")
    (pin "J31")
    (pin "J5")
    (pin "K10")
    (pin "K11")
    (pin "K13")
    (pin "K20")
    (pin "K22")
    (pin "K23")
    (pin "L10")
    (pin "L11")
    (pin "L12")
    (pin "L13")
    (pin "L14")
    (pin "L15")
    (pin "L16")
    (pin "L17")
    (pin "L18")
    (pin "L19")
    (pin "L20")
    (pin "L21")
    (pin "L22")
    (pin "L23")
    (pin "L28")
    (pin "L5")
    (pin "M11")
    (pin "M12")
    (pin "M13")
    (pin "M14")
    (pin "M15")
    (pin "M16")
    (pin "M17")
    (pin "M18")
    (pin "M19")
    (pin "M20")
    (pin "M21")
    (pin "M22")
    (pin "N10")
    (pin "N11")
    (pin "N12")
    (pin "N13")
    (pin "N14")
    (pin "N15")
    (pin "N16")
    (pin "N17")
    (pin "N18")
    (pin "N19")
    (pin "N2")
    (pin "N20")
    (pin "N21")
    (pin "N22")
    (pin "N23")
    (pin "N28")
    (pin "N31")
    (pin "N5")
    (pin "P11")
    (pin "P12")
    (pin "P13")
    (pin "P14")
    (pin "P15")
    (pin "P16")
    (pin "P17")
    (pin "P18")
    (pin "P19")
    (pin "P20")
    (pin "P21")
    (pin "P22")
    (pin "R11")
    (pin "R12")
    (pin "R13")
    (pin "R14")
    (pin "R15")
    (pin "R16")
    (pin "R17")
    (pin "R18")
    (pin "R19")
    (pin "R2")
    (pin "R20")
    (pin "R21")
    (pin "R22")
    (pin "R28")
    (pin "R31")
    (pin "R5")
    (pin "T11")
    (pin "T12")
    (pin "T13")
    (pin "T14")
    (pin "T15")
    (pin "T16")
    (pin "T17")
    (pin "T18")
    (pin "T19")
    (pin "T20")
    (pin "T21")
    (pin "T22")
    (pin "U11")
    (pin "U12")
    (pin "U13")
    (pin "U14")
    (pin "U15")
    (pin "U16")
    (pin "U17")
    (pin "U18")
    (pin "U19")
    (pin "U20")
    (pin "U21")
    (pin "U22")
    (pin "V11")
    (pin "V12")
    (pin "V13")
    (pin "V14")
    (pin "V15")
    (pin "V16")
    (pin "V17")
    (pin "V18")
    (pin "V19")
    (pin "V2")
    (pin "V20")
    (pin "V21")
    (pin "V22")
    (pin "V28")
    (pin "V3")
    (pin "V30")
    (pin "V31")
    (pin "V5")
    (pin "W11")
    (pin "W12")
    (pin "W13")
    (pin "W14")
    (pin "W15")
    (pin "W16")
    (pin "W17")
    (pin "W18")
    (pin "W19")
    (pin "W20")
    (pin "W21")
    (pin "W22")
    (pin "W27")
    (pin "W6")
    (pin "Y10")
    (pin "Y11")
    (pin "Y12")
    (pin "Y13")
    (pin "Y14")
    (pin "Y15")
    (pin "Y16")
    (pin "Y17")
    (pin "Y18")
    (pin "Y19")
    (pin "Y2")
    (pin "Y20")
    (pin "Y21")
    (pin "Y22")
    (pin "Y23")
    (pin "Y31")
    (pin "A10")
    (pin "A11")
    (pin "A13")
    (pin "A14")
    (pin "A15")
    (pin "A16")
    (pin "A17")
    (pin "A2")
    (pin "A3")
    (pin "A4")
    (pin "A5")
    (pin "A7")
    (pin "A8")
    (pin "A9")
    (pin "B10")
    (pin "B11")
    (pin "B14")
    (pin "B16")
    (pin "B17")
    (pin "B3")
    (pin "B4")
    (pin "B7")
    (pin "B8")
    (pin "C10")
    (pin "C11")
    (pin "C13")
    (pin "C14")
    (pin "C15")
    (pin "C16")
    (pin "C17")
    (pin "C7")
    (pin "C8")
    (pin "C9")
    (pin "D10")
    (pin "D11")
    (pin "D13")
    (pin "D14")
    (pin "D15")
    (pin "D16")
    (pin "D17")
    (pin "D7")
    (pin "D8")
    (pin "D9")
    (pin "E10")
    (pin "E11")
    (pin "E14")
    (pin "E16")
    (pin "E8")
    (pin "F10")
    (pin "F11")
    (pin "F13")
    (pin "F14")
    (pin "F15")
    (pin "F16")
    (pin "F8")
    (pin "F9")
    (pin "K12")
    (pin "K14")
    (pin "K15")
    (pin "K16")
    (pin "A18")
    (pin "A19")
    (pin "A20")
    (pin "A22")
    (pin "A23")
    (pin "A24")
    (pin "A25")
    (pin "A26")
    (pin "A28")
    (pin "A29")
    (pin "A30")
    (pin "A31")
    (pin "B19")
    (pin "B22")
    (pin "B23")
    (pin "B25")
    (pin "B26")
    (pin "B29")
    (pin "B30")
    (pin "C18")
    (pin "C19")
    (pin "C20")
    (pin "C22")
    (pin "C23")
    (pin "C24")
    (pin "C25")
    (pin "C26")
    (pin "D18")
    (pin "D19")
    (pin "D20")
    (pin "D22")
    (pin "D23")
    (pin "D24")
    (pin "D25")
    (pin "D26")
    (pin "E17")
    (pin "E19")
    (pin "E22")
    (pin "E23")
    (pin "E25")
    (pin "F17")
    (pin "F18")
    (pin "F19")
    (pin "F20")
    (pin "F22")
    (pin "F23")
    (pin "F24")
    (pin "F25")
    (pin "K17")
    (pin "K18")
    (pin "K19")
    (pin "K21")
    (pin "B32")
    (pin "C28")
    (pin "C29")
    (pin "C30")
    (pin "C31")
    (pin "C32")
    (pin "D28")
    (pin "D29")
    (pin "D30")
    (pin "D31")
    (pin "D32")
    (pin "E29")
    (pin "E30")
    (pin "E32")
    (pin "F28")
    (pin "F29")
    (pin "F30")
    (pin "F31")
    (pin "F32")
    (pin "H27")
    (pin "H28")
    (pin "H30")
    (pin "H31")
    (pin "H32")
    (pin "J26")
    (pin "J27")
    (pin "J29")
    (pin "J30")
    (pin "J32")
    (pin "K26")
    (pin "K27")
    (pin "K28")
    (pin "K29")
    (pin "K30")
    (pin "K31")
    (pin "K32")
    (pin "L26")
    (pin "L27")
    (pin "L29")
    (pin "L30")
    (pin "L31")
    (pin "L32")
    (pin "M23")
    (pin "N26")
    (pin "N27")
    (pin "N29")
    (pin "N30")
    (pin "P23")
    (pin "P26")
    (pin "P27")
    (pin "R23")
    (pin "T23")
    (pin "AA23")
    (pin "AB26")
    (pin "AB27")
    (pin "AB28")
    (pin "AB29")
    (pin "AB30")
    (pin "AB31")
    (pin "AB32")
    (pin "AC26")
    (pin "AC27")
    (pin "AC28")
    (pin "AC30")
    (pin "AC31")
    (pin "AC32")
    (pin "AD26")
    (pin "AD27")
    (pin "AD29")
    (pin "AD30")
    (pin "AD32")
    (pin "AE27")
    (pin "AE28")
    (pin "AE29")
    (pin "AE30")
    (pin "AE31")
    (pin "AE32")
    (pin "N32")
    (pin "P28")
    (pin "P29")
    (pin "P30")
    (pin "P31")
    (pin "P32")
    (pin "R26")
    (pin "R27")
    (pin "R29")
    (pin "R30")
    (pin "R32")
    (pin "T26")
    (pin "T27")
    (pin "T28")
    (pin "T29")
    (pin "T30")
    (pin "T31")
    (pin "T32")
    (pin "U23")
    (pin "U26")
    (pin "U27")
    (pin "U28")
    (pin "U29")
    (pin "U30")
    (pin "U31")
    (pin "U32")
    (pin "V23")
    (pin "V26")
    (pin "V27")
    (pin "V29")
    (pin "V32")
    (pin "W23")
    (pin "W28")
    (pin "W29")
    (pin "W30")
    (pin "W31")
    (pin "W32")
    (pin "Y26")
    (pin "Y27")
    (pin "Y28")
    (pin "Y29")
    (pin "Y30")
    (pin "Y32")
    (pin "AB23")
    (pin "AC23")
    (pin "AG28")
    (pin "AG29")
    (pin "AG30")
    (pin "AG32")
    (pin "AH28")
    (pin "AH30")
    (pin "AH32")
    (pin "AJ28")
    (pin "AJ29")
    (pin "AJ30")
    (pin "AJ31")
    (pin "AJ32")
    (pin "AK28")
    (pin "AK29")
    (pin "AK30")
    (pin "AK31")
    (pin "AK32")
    (pin "AL28")
    (pin "AL30")
    (pin "AL32")
    (pin "AM28")
    (pin "AM29")
    (pin "AM30")
    (pin "AM31")
    (pin "AA10")
    (pin "AB1")
    (pin "AB2")
    (pin "AB3")
    (pin "AB4")
    (pin "AB5")
    (pin "AB6")
    (pin "AB7")
    (pin "AC1")
    (pin "AC2")
    (pin "AC3")
    (pin "AC5")
    (pin "AC6")
    (pin "AC7")
    (pin "AD1")
    (pin "AD3")
    (pin "AD4")
    (pin "AD6")
    (pin "AD7")
    (pin "AE1")
    (pin "AE2")
    (pin "AE3")
    (pin "AE4")
    (pin "AE5")
    (pin "AE6")
    (pin "N1")
    (pin "P1")
    (pin "P2")
    (pin "P3")
    (pin "P4")
    (pin "P5")
    (pin "R1")
    (pin "R3")
    (pin "R4")
    (pin "R6")
    (pin "R7")
    (pin "T1")
    (pin "T2")
    (pin "T3")
    (pin "T4")
    (pin "T5")
    (pin "T6")
    (pin "T7")
    (pin "U1")
    (pin "U10")
    (pin "U2")
    (pin "U3")
    (pin "U4")
    (pin "U5")
    (pin "U6")
    (pin "U7")
    (pin "V1")
    (pin "V10")
    (pin "V4")
    (pin "V6")
    (pin "V7")
    (pin "W1")
    (pin "W10")
    (pin "W2")
    (pin "W3")
    (pin "W4")
    (pin "W5")
    (pin "Y1")
    (pin "Y3")
    (pin "Y4")
    (pin "Y5")
    (pin "Y6")
    (pin "Y7")
    (pin "B1")
    (pin "C1")
    (pin "C2")
    (pin "C3")
    (pin "C4")
    (pin "C5")
    (pin "D1")
    (pin "D2")
    (pin "D3")
    (pin "D4")
    (pin "D5")
    (pin "E1")
    (pin "E3")
    (pin "E4")
    (pin "F1")
    (pin "F2")
    (pin "F3")
    (pin "F4")
    (pin "F5")
    (pin "H1")
    (pin "H2")
    (pin "H3")
    (pin "H5")
    (pin "H6")
    (pin "J1")
    (pin "J3")
    (pin "J4")
    (pin "J6")
    (pin "J7")
    (pin "K1")
    (pin "K2")
    (pin "K3")
    (pin "K4")
    (pin "K5")
    (pin "K6")
    (pin "K7")
    (pin "L1")
    (pin "L2")
    (pin "L3")
    (pin "L4")
    (pin "L6")
    (pin "L7")
    (pin "M10")
    (pin "N3")
    (pin "N4")
    (pin "N6")
    (pin "N7")
    (pin "P10")
    (pin "P6")
    (pin "P7")
    (pin "R10")
    (pin "T10")
    (pin "AB10")
    (pin "AC10")
    (pin "AG1")
    (pin "AG3")
    (pin "AG4")
    (pin "AH1")
    (pin "AH3")
    (pin "AH4")
    (pin "AJ1")
    (pin "AJ2")
    (pin "AJ3")
    (pin "AJ4")
    (pin "AK1")
    (pin "AK2")
    (pin "AK3")
    (pin "AK4")
    (pin "AL1")
    (pin "AL3")
    (pin "AL4")
    (pin "AM2")
    (pin "AM3")
    (pin "AM4")
    (pin "AG5")
    (pin "AJ5")
    (pin "AK5")
    (pin "AM5")
    (pin "AK10")
    (pin "AK12")
    (pin "AK13")
    (pin "AK9")
    (pin "AM11")
    (pin "AM12")
    (pin "AM14")
    (pin "AM15")
    (pin "AM8")
    (pin "AM9")
    (pin "AK18")
    (pin "AK19")
    (pin "AK21")
    (pin "AK22")
    (pin "AM17")
    (pin "AM18")
    (pin "AM20")
    (pin "AM21")
    (pin "AM23")
    (pin "AM24")
    (instances
      (project "ecp5-dc-scm"
        (path ""
          (reference "U21") (unit 8)
        )
      )
    )
  )

  (symbol (lib_id "antmicroCapacitors0402:C_470n_0402") (at 114.3 30.48 90) (mirror x) (unit 1)
    (in_bom yes) (on_board yes) (dnp no) (fields_autoplaced)
    (property "Reference" "C213" (at 117.475 31.7563 90)
      (effects (font (size 1.524 1.524)) (justify right))
    )
    (property "Value" "C_470n_0402" (at 118.11 30.48 0)
      (effects (font (size 1.524 1.524)) hide)
    )
    (property "Footprint" "antmicro-footprints:C_0402_1005Metric" (at 109.22 35.56 0)
      (effects (font (size 1.524 1.524)) (justify left) hide)
    )
    (property "Datasheet" "https://product.tdk.com/en/search/capacitor/ceramic/mlcc/info?part_no=C1005X5R1E474M050BB" (at 114.3 30.48 0)
      (effects (font (size 1.27 1.27)) hide)
    )
    (property "Manufacturer" "TDK" (at 104.14 35.56 0)
      (effects (font (size 1.524 1.524)) (justify left) hide)
    )
    (property "MPN" "C1005X5R1E474M050BB" (at 106.68 35.56 0)
      (effects (font (size 1.524 1.524)) (justify left) hide)
    )
    (property "Val" "470n" (at 117.475 34.2963 90)
      (effects (font (size 1.27 1.27)) (justify right))
    )
    (property "License" "Apache-2.0" (at 137.16 50.8 0)
      (effects (font (size 1.27 1.27) (thickness 0.15)) (justify left bottom) hide)
    )
    (property "Author" "Antmicro" (at 139.7 50.8 0)
      (effects (font (size 1.27 1.27) (thickness 0.15)) (justify left bottom) hide)
    )
    (property "Voltage" "" (at 142.24 50.8 0)
      (effects (font (size 1.27 1.27)) (justify left bottom) hide)
    )
    (property "Dielectric" "" (at 144.78 50.8 0)
      (effects (font (size 1.27 1.27)) (justify left bottom) hide)
    )
    (property "Public" "False" (at 147.32 50.8 0)
      (effects (font (size 1.27 1.27)) (justify left bottom) hide)
    )
    (pin "1")
    (pin "2")
    (instances
      (project "ecp5-dc-scm"
        (path ""
          (reference "C213") (unit 1)
        )
      )
    )
  )

  (symbol (lib_id "antmicroCapacitors0402:C_470n_0402") (at 104.14 30.48 270) (unit 1)
    (in_bom yes) (on_board yes) (dnp no)
    (property "Reference" "C211" (at 107.315 31.7563 90)
      (effects (font (size 1.524 1.524)) (justify left))
    )
    (property "Value" "C_470n_0402" (at 100.33 30.48 0)
      (effects (font (size 1.524 1.524)) hide)
    )
    (property "Footprint" "antmicro-footprints:C_0402_1005Metric" (at 109.22 35.56 0)
      (effects (font (size 1.524 1.524)) (justify left) hide)
    )
    (property "Datasheet" "https://product.tdk.com/en/search/capacitor/ceramic/mlcc/info?part_no=C1005X5R1E474M050BB" (at 104.14 30.48 0)
      (effects (font (size 1.27 1.27)) hide)
    )
    (property "Manufacturer" "TDK" (at 114.3 35.56 0)
      (effects (font (size 1.524 1.524)) (justify left) hide)
    )
    (property "MPN" "C1005X5R1E474M050BB" (at 111.76 35.56 0)
      (effects (font (size 1.524 1.524)) (justify left) hide)
    )
    (property "Val" "470n" (at 107.315 34.2963 90)
      (effects (font (size 1.27 1.27)) (justify left))
    )
    (property "License" "Apache-2.0" (at 81.28 50.8 0)
      (effects (font (size 1.27 1.27) (thickness 0.15)) (justify left bottom) hide)
    )
    (property "Author" "Antmicro" (at 78.74 50.8 0)
      (effects (font (size 1.27 1.27) (thickness 0.15)) (justify left bottom) hide)
    )
    (property "Voltage" "" (at 76.2 50.8 0)
      (effects (font (size 1.27 1.27)) (justify left bottom) hide)
    )
    (property "Dielectric" "" (at 73.66 50.8 0)
      (effects (font (size 1.27 1.27)) (justify left bottom) hide)
    )
    (property "Public" "False" (at 71.12 50.8 0)
      (effects (font (size 1.27 1.27)) (justify left bottom) hide)
    )
    (pin "1")
    (pin "2")
    (instances
      (project "ecp5-dc-scm"
        (path ""
          (reference "C211") (unit 1)
        )
      )
    )
  )

  (symbol (lib_id "antmicroCapacitors0402:C_4u7_0402") (at 93.98 30.48 270) (unit 1)
    (in_bom yes) (on_board yes) (dnp no)
    (property "Reference" "C209" (at 96.52 31.7563 90)
      (effects (font (size 1.524 1.524)) (justify left))
    )
    (property "Value" "C_4u7_0402" (at 90.17 30.48 0)
      (effects (font (size 1.524 1.524)) hide)
    )
    (property "Footprint" "antmicro-footprints:C_0402_1005Metric" (at 99.06 35.56 0)
      (effects (font (size 1.524 1.524)) (justify left) hide)
    )
    (property "Datasheet" "https://www.murata.com/products/productdetail?partno=GRM155R61A475MEAA%23" (at 93.98 30.48 0)
      (effects (font (size 1.27 1.27)) hide)
    )
    (property "Manufacturer" "Murata" (at 104.14 35.56 0)
      (effects (font (size 1.524 1.524)) (justify left) hide)
    )
    (property "MPN" "GRM155R61A475MEAAD" (at 101.6 35.56 0)
      (effects (font (size 1.524 1.524)) (justify left) hide)
    )
    (property "Val" "4u7" (at 96.52 34.2963 90)
      (effects (font (size 1.27 1.27)) (justify left))
    )
    (property "License" "Apache-2.0" (at 71.12 50.8 0)
      (effects (font (size 1.27 1.27) (thickness 0.15)) (justify left bottom) hide)
    )
    (property "Author" "Antmicro" (at 68.58 50.8 0)
      (effects (font (size 1.27 1.27) (thickness 0.15)) (justify left bottom) hide)
    )
    (property "Voltage" "" (at 66.04 50.8 0)
      (effects (font (size 1.27 1.27)) (justify left bottom) hide)
    )
    (property "Dielectric" "" (at 63.5 50.8 0)
      (effects (font (size 1.27 1.27)) (justify left bottom) hide)
    )
    (property "Public" "False" (at 60.96 50.8 0)
      (effects (font (size 1.27 1.27)) (justify left bottom) hide)
    )
    (pin "1")
    (pin "2")
    (instances
      (project "ecp5-dc-scm"
        (path ""
          (reference "C209") (unit 1)
        )
      )
    )
  )

  (symbol (lib_id "antmicroCapacitors0402:C_470n_0402") (at 198.12 30.48 270) (unit 1)
    (in_bom yes) (on_board yes) (dnp no)
    (property "Reference" "C224" (at 201.295 31.75 90)
      (effects (font (size 1.524 1.524)) (justify left))
    )
    (property "Value" "C_470n_0402" (at 194.31 30.48 0)
      (effects (font (size 1.524 1.524)) hide)
    )
    (property "Footprint" "antmicro-footprints:C_0402_1005Metric" (at 203.2 35.56 0)
      (effects (font (size 1.524 1.524)) (justify left) hide)
    )
    (property "Datasheet" "https://product.tdk.com/en/search/capacitor/ceramic/mlcc/info?part_no=C1005X5R1E474M050BB" (at 198.12 30.48 0)
      (effects (font (size 1.27 1.27)) hide)
    )
    (property "Manufacturer" "TDK" (at 208.28 35.56 0)
      (effects (font (size 1.524 1.524)) (justify left) hide)
    )
    (property "MPN" "C1005X5R1E474M050BB" (at 205.74 35.56 0)
      (effects (font (size 1.524 1.524)) (justify left) hide)
    )
    (property "Val" "470n" (at 201.295 34.29 90)
      (effects (font (size 1.27 1.27)) (justify left))
    )
    (property "License" "Apache-2.0" (at 175.26 50.8 0)
      (effects (font (size 1.27 1.27) (thickness 0.15)) (justify left bottom) hide)
    )
    (property "Author" "Antmicro" (at 172.72 50.8 0)
      (effects (font (size 1.27 1.27) (thickness 0.15)) (justify left bottom) hide)
    )
    (property "Voltage" "" (at 170.18 50.8 0)
      (effects (font (size 1.27 1.27)) (justify left bottom) hide)
    )
    (property "Dielectric" "" (at 167.64 50.8 0)
      (effects (font (size 1.27 1.27)) (justify left bottom) hide)
    )
    (property "Public" "False" (at 165.1 50.8 0)
      (effects (font (size 1.27 1.27)) (justify left bottom) hide)
    )
    (pin "1")
    (pin "2")
    (instances
      (project "ecp5-dc-scm"
        (path ""
          (reference "C224") (unit 1)
        )
      )
    )
  )

  (symbol (lib_id "antmicroCapacitors0402:C_470n_0402") (at 177.8 30.48 270) (unit 1)
    (in_bom yes) (on_board yes) (dnp no)
    (property "Reference" "C222" (at 180.34 31.7563 90)
      (effects (font (size 1.524 1.524)) (justify left))
    )
    (property "Value" "C_470n_0402" (at 173.99 30.48 0)
      (effects (font (size 1.524 1.524)) hide)
    )
    (property "Footprint" "antmicro-footprints:C_0402_1005Metric" (at 182.88 35.56 0)
      (effects (font (size 1.524 1.524)) (justify left) hide)
    )
    (property "Datasheet" "https://product.tdk.com/en/search/capacitor/ceramic/mlcc/info?part_no=C1005X5R1E474M050BB" (at 177.8 30.48 0)
      (effects (font (size 1.27 1.27)) hide)
    )
    (property "Manufacturer" "TDK" (at 187.96 35.56 0)
      (effects (font (size 1.524 1.524)) (justify left) hide)
    )
    (property "MPN" "C1005X5R1E474M050BB" (at 185.42 35.56 0)
      (effects (font (size 1.524 1.524)) (justify left) hide)
    )
    (property "Val" "470n" (at 180.34 34.2963 90)
      (effects (font (size 1.27 1.27)) (justify left))
    )
    (property "License" "Apache-2.0" (at 154.94 50.8 0)
      (effects (font (size 1.27 1.27) (thickness 0.15)) (justify left bottom) hide)
    )
    (property "Author" "Antmicro" (at 152.4 50.8 0)
      (effects (font (size 1.27 1.27) (thickness 0.15)) (justify left bottom) hide)
    )
    (property "Voltage" "" (at 149.86 50.8 0)
      (effects (font (size 1.27 1.27)) (justify left bottom) hide)
    )
    (property "Dielectric" "" (at 147.32 50.8 0)
      (effects (font (size 1.27 1.27)) (justify left bottom) hide)
    )
    (property "Public" "False" (at 144.78 50.8 0)
      (effects (font (size 1.27 1.27)) (justify left bottom) hide)
    )
    (pin "1")
    (pin "2")
    (instances
      (project "ecp5-dc-scm"
        (path ""
          (reference "C222") (unit 1)
        )
      )
    )
  )

  (symbol (lib_id "antmicroCapacitors0402:C_470n_0402") (at 167.64 30.48 270) (unit 1)
    (in_bom yes) (on_board yes) (dnp no) (fields_autoplaced)
    (property "Reference" "C221" (at 170.18 31.7563 90)
      (effects (font (size 1.524 1.524)) (justify left))
    )
    (property "Value" "C_470n_0402" (at 163.83 30.48 0)
      (effects (font (size 1.524 1.524)) hide)
    )
    (property "Footprint" "antmicro-footprints:C_0402_1005Metric" (at 172.72 35.56 0)
      (effects (font (size 1.524 1.524)) (justify left) hide)
    )
    (property "Datasheet" "https://product.tdk.com/en/search/capacitor/ceramic/mlcc/info?part_no=C1005X5R1E474M050BB" (at 167.64 30.48 0)
      (effects (font (size 1.27 1.27)) hide)
    )
    (property "Manufacturer" "TDK" (at 177.8 35.56 0)
      (effects (font (size 1.524 1.524)) (justify left) hide)
    )
    (property "MPN" "C1005X5R1E474M050BB" (at 175.26 35.56 0)
      (effects (font (size 1.524 1.524)) (justify left) hide)
    )
    (property "Val" "470n" (at 170.18 34.2963 90)
      (effects (font (size 1.27 1.27)) (justify left))
    )
    (property "License" "Apache-2.0" (at 144.78 50.8 0)
      (effects (font (size 1.27 1.27) (thickness 0.15)) (justify left bottom) hide)
    )
    (property "Author" "Antmicro" (at 142.24 50.8 0)
      (effects (font (size 1.27 1.27) (thickness 0.15)) (justify left bottom) hide)
    )
    (property "Voltage" "" (at 139.7 50.8 0)
      (effects (font (size 1.27 1.27)) (justify left bottom) hide)
    )
    (property "Dielectric" "" (at 137.16 50.8 0)
      (effects (font (size 1.27 1.27)) (justify left bottom) hide)
    )
    (property "Public" "False" (at 134.62 50.8 0)
      (effects (font (size 1.27 1.27)) (justify left bottom) hide)
    )
    (pin "1")
    (pin "2")
    (instances
      (project "ecp5-dc-scm"
        (path ""
          (reference "C221") (unit 1)
        )
      )
    )
  )

  (symbol (lib_id "antmicroCapacitors0402:C_4u7_0402") (at 157.48 30.48 270) (unit 1)
    (in_bom yes) (on_board yes) (dnp no) (fields_autoplaced)
    (property "Reference" "C219" (at 160.655 31.7563 90)
      (effects (font (size 1.524 1.524)) (justify left))
    )
    (property "Value" "C_4u7_0402" (at 153.67 30.48 0)
      (effects (font (size 1.524 1.524)) hide)
    )
    (property "Footprint" "antmicro-footprints:C_0402_1005Metric" (at 162.56 35.56 0)
      (effects (font (size 1.524 1.524)) (justify left) hide)
    )
    (property "Datasheet" "https://www.murata.com/products/productdetail?partno=GRM155R61A475MEAA%23" (at 157.48 30.48 0)
      (effects (font (size 1.27 1.27)) hide)
    )
    (property "Manufacturer" "Murata" (at 167.64 35.56 0)
      (effects (font (size 1.524 1.524)) (justify left) hide)
    )
    (property "MPN" "GRM155R61A475MEAAD" (at 165.1 35.56 0)
      (effects (font (size 1.524 1.524)) (justify left) hide)
    )
    (property "Val" "4u7" (at 160.655 34.2963 90)
      (effects (font (size 1.27 1.27)) (justify left))
    )
    (property "License" "Apache-2.0" (at 134.62 50.8 0)
      (effects (font (size 1.27 1.27) (thickness 0.15)) (justify left bottom) hide)
    )
    (property "Author" "Antmicro" (at 132.08 50.8 0)
      (effects (font (size 1.27 1.27) (thickness 0.15)) (justify left bottom) hide)
    )
    (property "Voltage" "" (at 129.54 50.8 0)
      (effects (font (size 1.27 1.27)) (justify left bottom) hide)
    )
    (property "Dielectric" "" (at 127 50.8 0)
      (effects (font (size 1.27 1.27)) (justify left bottom) hide)
    )
    (property "Public" "False" (at 124.46 50.8 0)
      (effects (font (size 1.27 1.27)) (justify left bottom) hide)
    )
    (pin "1")
    (pin "2")
    (instances
      (project "ecp5-dc-scm"
        (path ""
          (reference "C219") (unit 1)
        )
      )
    )
  )

  (symbol (lib_id "antmicroCapacitors0402:C_470n_0402") (at 260.35 30.48 90) (mirror x) (unit 1)
    (in_bom yes) (on_board yes) (dnp no) (fields_autoplaced)
    (property "Reference" "C229" (at 263.525 31.7563 90)
      (effects (font (size 1.524 1.524)) (justify right))
    )
    (property "Value" "C_470n_0402" (at 264.16 30.48 0)
      (effects (font (size 1.524 1.524)) hide)
    )
    (property "Footprint" "antmicro-footprints:C_0402_1005Metric" (at 255.27 35.56 0)
      (effects (font (size 1.524 1.524)) (justify left) hide)
    )
    (property "Datasheet" "https://product.tdk.com/en/search/capacitor/ceramic/mlcc/info?part_no=C1005X5R1E474M050BB" (at 260.35 30.48 0)
      (effects (font (size 1.27 1.27)) hide)
    )
    (property "Manufacturer" "TDK" (at 250.19 35.56 0)
      (effects (font (size 1.524 1.524)) (justify left) hide)
    )
    (property "MPN" "C1005X5R1E474M050BB" (at 252.73 35.56 0)
      (effects (font (size 1.524 1.524)) (justify left) hide)
    )
    (property "Val" "470n" (at 263.525 34.2963 90)
      (effects (font (size 1.27 1.27)) (justify right))
    )
    (property "License" "Apache-2.0" (at 283.21 50.8 0)
      (effects (font (size 1.27 1.27) (thickness 0.15)) (justify left bottom) hide)
    )
    (property "Author" "Antmicro" (at 285.75 50.8 0)
      (effects (font (size 1.27 1.27) (thickness 0.15)) (justify left bottom) hide)
    )
    (property "Voltage" "" (at 288.29 50.8 0)
      (effects (font (size 1.27 1.27)) (justify left bottom) hide)
    )
    (property "Dielectric" "" (at 290.83 50.8 0)
      (effects (font (size 1.27 1.27)) (justify left bottom) hide)
    )
    (property "Public" "False" (at 293.37 50.8 0)
      (effects (font (size 1.27 1.27)) (justify left bottom) hide)
    )
    (pin "1")
    (pin "2")
    (instances
      (project "ecp5-dc-scm"
        (path ""
          (reference "C229") (unit 1)
        )
      )
    )
  )

  (symbol (lib_id "antmicroCapacitors0402:C_470n_0402") (at 250.19 30.48 90) (mirror x) (unit 1)
    (in_bom yes) (on_board yes) (dnp no) (fields_autoplaced)
    (property "Reference" "C228" (at 252.73 31.7563 90)
      (effects (font (size 1.524 1.524)) (justify right))
    )
    (property "Value" "C_470n_0402" (at 254 30.48 0)
      (effects (font (size 1.524 1.524)) hide)
    )
    (property "Footprint" "antmicro-footprints:C_0402_1005Metric" (at 245.11 35.56 0)
      (effects (font (size 1.524 1.524)) (justify left) hide)
    )
    (property "Datasheet" "https://product.tdk.com/en/search/capacitor/ceramic/mlcc/info?part_no=C1005X5R1E474M050BB" (at 250.19 30.48 0)
      (effects (font (size 1.27 1.27)) hide)
    )
    (property "Manufacturer" "TDK" (at 240.03 35.56 0)
      (effects (font (size 1.524 1.524)) (justify left) hide)
    )
    (property "MPN" "C1005X5R1E474M050BB" (at 242.57 35.56 0)
      (effects (font (size 1.524 1.524)) (justify left) hide)
    )
    (property "Val" "470n" (at 252.73 34.2963 90)
      (effects (font (size 1.27 1.27)) (justify right))
    )
    (property "License" "Apache-2.0" (at 273.05 50.8 0)
      (effects (font (size 1.27 1.27) (thickness 0.15)) (justify left bottom) hide)
    )
    (property "Author" "Antmicro" (at 275.59 50.8 0)
      (effects (font (size 1.27 1.27) (thickness 0.15)) (justify left bottom) hide)
    )
    (property "Voltage" "" (at 278.13 50.8 0)
      (effects (font (size 1.27 1.27)) (justify left bottom) hide)
    )
    (property "Dielectric" "" (at 280.67 50.8 0)
      (effects (font (size 1.27 1.27)) (justify left bottom) hide)
    )
    (property "Public" "False" (at 283.21 50.8 0)
      (effects (font (size 1.27 1.27)) (justify left bottom) hide)
    )
    (pin "1")
    (pin "2")
    (instances
      (project "ecp5-dc-scm"
        (path ""
          (reference "C228") (unit 1)
        )
      )
    )
  )

  (symbol (lib_id "antmicroCapacitors0402:C_470n_0402") (at 331.47 30.48 90) (mirror x) (unit 1)
    (in_bom yes) (on_board yes) (dnp no) (fields_autoplaced)
    (property "Reference" "C234" (at 334.01 31.7563 90)
      (effects (font (size 1.524 1.524)) (justify right))
    )
    (property "Value" "C_470n_0402" (at 335.28 30.48 0)
      (effects (font (size 1.524 1.524)) hide)
    )
    (property "Footprint" "antmicro-footprints:C_0402_1005Metric" (at 326.39 35.56 0)
      (effects (font (size 1.524 1.524)) (justify left) hide)
    )
    (property "Datasheet" "https://product.tdk.com/en/search/capacitor/ceramic/mlcc/info?part_no=C1005X5R1E474M050BB" (at 331.47 30.48 0)
      (effects (font (size 1.27 1.27)) hide)
    )
    (property "Manufacturer" "TDK" (at 321.31 35.56 0)
      (effects (font (size 1.524 1.524)) (justify left) hide)
    )
    (property "MPN" "C1005X5R1E474M050BB" (at 323.85 35.56 0)
      (effects (font (size 1.524 1.524)) (justify left) hide)
    )
    (property "Val" "470n" (at 334.01 34.2963 90)
      (effects (font (size 1.27 1.27)) (justify right))
    )
    (property "License" "Apache-2.0" (at 354.33 50.8 0)
      (effects (font (size 1.27 1.27) (thickness 0.15)) (justify left bottom) hide)
    )
    (property "Author" "Antmicro" (at 356.87 50.8 0)
      (effects (font (size 1.27 1.27) (thickness 0.15)) (justify left bottom) hide)
    )
    (property "Voltage" "" (at 359.41 50.8 0)
      (effects (font (size 1.27 1.27)) (justify left bottom) hide)
    )
    (property "Dielectric" "" (at 361.95 50.8 0)
      (effects (font (size 1.27 1.27)) (justify left bottom) hide)
    )
    (property "Public" "False" (at 364.49 50.8 0)
      (effects (font (size 1.27 1.27)) (justify left bottom) hide)
    )
    (pin "1")
    (pin "2")
    (instances
      (project "ecp5-dc-scm"
        (path ""
          (reference "C234") (unit 1)
        )
      )
    )
  )

  (symbol (lib_id "antmicroCapacitors0402:C_470n_0402") (at 321.31 30.48 90) (mirror x) (unit 1)
    (in_bom yes) (on_board yes) (dnp no) (fields_autoplaced)
    (property "Reference" "C233" (at 324.485 31.7563 90)
      (effects (font (size 1.524 1.524)) (justify right))
    )
    (property "Value" "C_470n_0402" (at 325.12 30.48 0)
      (effects (font (size 1.524 1.524)) hide)
    )
    (property "Footprint" "antmicro-footprints:C_0402_1005Metric" (at 316.23 35.56 0)
      (effects (font (size 1.524 1.524)) (justify left) hide)
    )
    (property "Datasheet" "https://product.tdk.com/en/search/capacitor/ceramic/mlcc/info?part_no=C1005X5R1E474M050BB" (at 321.31 30.48 0)
      (effects (font (size 1.27 1.27)) hide)
    )
    (property "Manufacturer" "TDK" (at 311.15 35.56 0)
      (effects (font (size 1.524 1.524)) (justify left) hide)
    )
    (property "MPN" "C1005X5R1E474M050BB" (at 313.69 35.56 0)
      (effects (font (size 1.524 1.524)) (justify left) hide)
    )
    (property "Val" "470n" (at 324.485 34.2963 90)
      (effects (font (size 1.27 1.27)) (justify right))
    )
    (property "License" "Apache-2.0" (at 344.17 50.8 0)
      (effects (font (size 1.27 1.27) (thickness 0.15)) (justify left bottom) hide)
    )
    (property "Author" "Antmicro" (at 346.71 50.8 0)
      (effects (font (size 1.27 1.27) (thickness 0.15)) (justify left bottom) hide)
    )
    (property "Voltage" "" (at 349.25 50.8 0)
      (effects (font (size 1.27 1.27)) (justify left bottom) hide)
    )
    (property "Dielectric" "" (at 351.79 50.8 0)
      (effects (font (size 1.27 1.27)) (justify left bottom) hide)
    )
    (property "Public" "False" (at 354.33 50.8 0)
      (effects (font (size 1.27 1.27)) (justify left bottom) hide)
    )
    (pin "1")
    (pin "2")
    (instances
      (project "ecp5-dc-scm"
        (path ""
          (reference "C233") (unit 1)
        )
      )
    )
  )

  (symbol (lib_id "antmicroCapacitors0402:C_4u7_0402") (at 288.29 30.48 270) (unit 1)
    (in_bom yes) (on_board yes) (dnp no)
    (property "Reference" "C230" (at 291.465 31.7563 90)
      (effects (font (size 1.524 1.524)) (justify left))
    )
    (property "Value" "C_4u7_0402" (at 284.48 30.48 0)
      (effects (font (size 1.524 1.524)) hide)
    )
    (property "Footprint" "antmicro-footprints:C_0402_1005Metric" (at 293.37 35.56 0)
      (effects (font (size 1.524 1.524)) (justify left) hide)
    )
    (property "Datasheet" "https://www.murata.com/products/productdetail?partno=GRM155R61A475MEAA%23" (at 288.29 30.48 0)
      (effects (font (size 1.27 1.27)) hide)
    )
    (property "Manufacturer" "Murata" (at 298.45 35.56 0)
      (effects (font (size 1.524 1.524)) (justify left) hide)
    )
    (property "MPN" "GRM155R61A475MEAAD" (at 295.91 35.56 0)
      (effects (font (size 1.524 1.524)) (justify left) hide)
    )
    (property "Val" "4u7" (at 291.465 34.2963 90)
      (effects (font (size 1.27 1.27)) (justify left))
    )
    (property "License" "Apache-2.0" (at 265.43 50.8 0)
      (effects (font (size 1.27 1.27) (thickness 0.15)) (justify left bottom) hide)
    )
    (property "Author" "Antmicro" (at 262.89 50.8 0)
      (effects (font (size 1.27 1.27) (thickness 0.15)) (justify left bottom) hide)
    )
    (property "Voltage" "" (at 260.35 50.8 0)
      (effects (font (size 1.27 1.27)) (justify left bottom) hide)
    )
    (property "Dielectric" "" (at 257.81 50.8 0)
      (effects (font (size 1.27 1.27)) (justify left bottom) hide)
    )
    (property "Public" "False" (at 255.27 50.8 0)
      (effects (font (size 1.27 1.27)) (justify left bottom) hide)
    )
    (pin "1")
    (pin "2")
    (instances
      (project "ecp5-dc-scm"
        (path ""
          (reference "C230") (unit 1)
        )
      )
    )
  )

  (symbol (lib_id "antmicroCapacitors0402:C_470n_0402") (at 391.16 29.21 90) (mirror x) (unit 1)
    (in_bom yes) (on_board yes) (dnp no)
    (property "Reference" "C239" (at 392.43 30.226 90)
      (effects (font (size 1.524 1.524)) (justify right))
    )
    (property "Value" "C_470n_0402" (at 394.97 29.21 0)
      (effects (font (size 1.524 1.524)) hide)
    )
    (property "Footprint" "antmicro-footprints:C_0402_1005Metric" (at 386.08 34.29 0)
      (effects (font (size 1.524 1.524)) (justify left) hide)
    )
    (property "Datasheet" "https://product.tdk.com/en/search/capacitor/ceramic/mlcc/info?part_no=C1005X5R1E474M050BB" (at 391.16 29.21 0)
      (effects (font (size 1.27 1.27)) hide)
    )
    (property "Manufacturer" "TDK" (at 381 34.29 0)
      (effects (font (size 1.524 1.524)) (justify left) hide)
    )
    (property "MPN" "C1005X5R1E474M050BB" (at 383.54 34.29 0)
      (effects (font (size 1.524 1.524)) (justify left) hide)
    )
    (property "Val" "470n" (at 392.43 33.274 90)
      (effects (font (size 1.27 1.27)) (justify right))
    )
    (property "License" "Apache-2.0" (at 414.02 49.53 0)
      (effects (font (size 1.27 1.27) (thickness 0.15)) (justify left bottom) hide)
    )
    (property "Author" "Antmicro" (at 416.56 49.53 0)
      (effects (font (size 1.27 1.27) (thickness 0.15)) (justify left bottom) hide)
    )
    (property "Voltage" "" (at 419.1 49.53 0)
      (effects (font (size 1.27 1.27)) (justify left bottom) hide)
    )
    (property "Dielectric" "" (at 421.64 49.53 0)
      (effects (font (size 1.27 1.27)) (justify left bottom) hide)
    )
    (property "Public" "False" (at 424.18 49.53 0)
      (effects (font (size 1.27 1.27)) (justify left bottom) hide)
    )
    (pin "1")
    (pin "2")
    (instances
      (project "ecp5-dc-scm"
        (path ""
          (reference "C239") (unit 1)
        )
      )
    )
  )

  (symbol (lib_id "antmicroCapacitors0402:C_470n_0402") (at 381 29.21 90) (mirror x) (unit 1)
    (in_bom yes) (on_board yes) (dnp no)
    (property "Reference" "C238" (at 382.778 30.48 90)
      (effects (font (size 1.524 1.524)) (justify right))
    )
    (property "Value" "C_470n_0402" (at 384.81 29.21 0)
      (effects (font (size 1.524 1.524)) hide)
    )
    (property "Footprint" "antmicro-footprints:C_0402_1005Metric" (at 375.92 34.29 0)
      (effects (font (size 1.524 1.524)) (justify left) hide)
    )
    (property "Datasheet" "https://product.tdk.com/en/search/capacitor/ceramic/mlcc/info?part_no=C1005X5R1E474M050BB" (at 381 29.21 0)
      (effects (font (size 1.27 1.27)) hide)
    )
    (property "Manufacturer" "TDK" (at 370.84 34.29 0)
      (effects (font (size 1.524 1.524)) (justify left) hide)
    )
    (property "MPN" "C1005X5R1E474M050BB" (at 373.38 34.29 0)
      (effects (font (size 1.524 1.524)) (justify left) hide)
    )
    (property "Val" "470n" (at 382.778 33.02 90)
      (effects (font (size 1.27 1.27)) (justify right))
    )
    (property "License" "Apache-2.0" (at 403.86 49.53 0)
      (effects (font (size 1.27 1.27) (thickness 0.15)) (justify left bottom) hide)
    )
    (property "Author" "Antmicro" (at 406.4 49.53 0)
      (effects (font (size 1.27 1.27) (thickness 0.15)) (justify left bottom) hide)
    )
    (property "Voltage" "" (at 408.94 49.53 0)
      (effects (font (size 1.27 1.27)) (justify left bottom) hide)
    )
    (property "Dielectric" "" (at 411.48 49.53 0)
      (effects (font (size 1.27 1.27)) (justify left bottom) hide)
    )
    (property "Public" "False" (at 414.02 49.53 0)
      (effects (font (size 1.27 1.27)) (justify left bottom) hide)
    )
    (pin "1")
    (pin "2")
    (instances
      (project "ecp5-dc-scm"
        (path ""
          (reference "C238") (unit 1)
        )
      )
    )
  )

  (symbol (lib_id "antmicroCapacitors0402:C_470n_0402") (at 372.11 29.21 90) (mirror x) (unit 1)
    (in_bom yes) (on_board yes) (dnp no)
    (property "Reference" "C237" (at 373.38 30.226 90)
      (effects (font (size 1.524 1.524)) (justify right))
    )
    (property "Value" "C_470n_0402" (at 375.92 29.21 0)
      (effects (font (size 1.524 1.524)) hide)
    )
    (property "Footprint" "antmicro-footprints:C_0402_1005Metric" (at 367.03 34.29 0)
      (effects (font (size 1.524 1.524)) (justify left) hide)
    )
    (property "Datasheet" "https://product.tdk.com/en/search/capacitor/ceramic/mlcc/info?part_no=C1005X5R1E474M050BB" (at 372.11 29.21 0)
      (effects (font (size 1.27 1.27)) hide)
    )
    (property "Manufacturer" "TDK" (at 361.95 34.29 0)
      (effects (font (size 1.524 1.524)) (justify left) hide)
    )
    (property "MPN" "C1005X5R1E474M050BB" (at 364.49 34.29 0)
      (effects (font (size 1.524 1.524)) (justify left) hide)
    )
    (property "Val" "470n" (at 373.38 33.274 90)
      (effects (font (size 1.27 1.27)) (justify right))
    )
    (property "License" "Apache-2.0" (at 394.97 49.53 0)
      (effects (font (size 1.27 1.27) (thickness 0.15)) (justify left bottom) hide)
    )
    (property "Author" "Antmicro" (at 397.51 49.53 0)
      (effects (font (size 1.27 1.27) (thickness 0.15)) (justify left bottom) hide)
    )
    (property "Voltage" "" (at 400.05 49.53 0)
      (effects (font (size 1.27 1.27)) (justify left bottom) hide)
    )
    (property "Dielectric" "" (at 402.59 49.53 0)
      (effects (font (size 1.27 1.27)) (justify left bottom) hide)
    )
    (property "Public" "False" (at 405.13 49.53 0)
      (effects (font (size 1.27 1.27)) (justify left bottom) hide)
    )
    (pin "1")
    (pin "2")
    (instances
      (project "ecp5-dc-scm"
        (path ""
          (reference "C237") (unit 1)
        )
      )
    )
  )

  (symbol (lib_id "antmicroCapacitors0402:C_470n_0402") (at 363.22 29.21 270) (unit 1)
    (in_bom yes) (on_board yes) (dnp no)
    (property "Reference" "C236" (at 365.76 30.4863 90)
      (effects (font (size 1.524 1.524)) (justify left))
    )
    (property "Value" "C_470n_0402" (at 359.41 29.21 0)
      (effects (font (size 1.524 1.524)) hide)
    )
    (property "Footprint" "antmicro-footprints:C_0402_1005Metric" (at 368.3 34.29 0)
      (effects (font (size 1.524 1.524)) (justify left) hide)
    )
    (property "Datasheet" "https://product.tdk.com/en/search/capacitor/ceramic/mlcc/info?part_no=C1005X5R1E474M050BB" (at 363.22 29.21 0)
      (effects (font (size 1.27 1.27)) hide)
    )
    (property "Manufacturer" "TDK" (at 373.38 34.29 0)
      (effects (font (size 1.524 1.524)) (justify left) hide)
    )
    (property "MPN" "C1005X5R1E474M050BB" (at 370.84 34.29 0)
      (effects (font (size 1.524 1.524)) (justify left) hide)
    )
    (property "Val" "470n" (at 365.76 33.0263 90)
      (effects (font (size 1.27 1.27)) (justify left))
    )
    (property "License" "Apache-2.0" (at 340.36 49.53 0)
      (effects (font (size 1.27 1.27) (thickness 0.15)) (justify left bottom) hide)
    )
    (property "Author" "Antmicro" (at 337.82 49.53 0)
      (effects (font (size 1.27 1.27) (thickness 0.15)) (justify left bottom) hide)
    )
    (property "Voltage" "" (at 335.28 49.53 0)
      (effects (font (size 1.27 1.27)) (justify left bottom) hide)
    )
    (property "Dielectric" "" (at 332.74 49.53 0)
      (effects (font (size 1.27 1.27)) (justify left bottom) hide)
    )
    (property "Public" "False" (at 330.2 49.53 0)
      (effects (font (size 1.27 1.27)) (justify left bottom) hide)
    )
    (pin "1")
    (pin "2")
    (instances
      (project "ecp5-dc-scm"
        (path ""
          (reference "C236") (unit 1)
        )
      )
    )
  )

  (symbol (lib_id "antmicroCapacitors0402:C_470n_0402") (at 109.22 187.96 90) (mirror x) (unit 1)
    (in_bom yes) (on_board yes) (dnp no) (fields_autoplaced)
    (property "Reference" "C212" (at 111.76 189.2363 90)
      (effects (font (size 1.524 1.524)) (justify right))
    )
    (property "Value" "C_470n_0402" (at 113.03 187.96 0)
      (effects (font (size 1.524 1.524)) hide)
    )
    (property "Footprint" "antmicro-footprints:C_0402_1005Metric" (at 104.14 193.04 0)
      (effects (font (size 1.524 1.524)) (justify left) hide)
    )
    (property "Datasheet" "https://product.tdk.com/en/search/capacitor/ceramic/mlcc/info?part_no=C1005X5R1E474M050BB" (at 109.22 187.96 0)
      (effects (font (size 1.27 1.27)) hide)
    )
    (property "Manufacturer" "TDK" (at 99.06 193.04 0)
      (effects (font (size 1.524 1.524)) (justify left) hide)
    )
    (property "MPN" "C1005X5R1E474M050BB" (at 101.6 193.04 0)
      (effects (font (size 1.524 1.524)) (justify left) hide)
    )
    (property "Val" "470n" (at 111.76 191.7763 90)
      (effects (font (size 1.27 1.27)) (justify right))
    )
    (property "License" "Apache-2.0" (at 132.08 208.28 0)
      (effects (font (size 1.27 1.27) (thickness 0.15)) (justify left bottom) hide)
    )
    (property "Author" "Antmicro" (at 134.62 208.28 0)
      (effects (font (size 1.27 1.27) (thickness 0.15)) (justify left bottom) hide)
    )
    (property "Voltage" "" (at 137.16 208.28 0)
      (effects (font (size 1.27 1.27)) (justify left bottom) hide)
    )
    (property "Dielectric" "" (at 139.7 208.28 0)
      (effects (font (size 1.27 1.27)) (justify left bottom) hide)
    )
    (property "Public" "False" (at 142.24 208.28 0)
      (effects (font (size 1.27 1.27)) (justify left bottom) hide)
    )
    (pin "1")
    (pin "2")
    (instances
      (project "ecp5-dc-scm"
        (path ""
          (reference "C212") (unit 1)
        )
      )
    )
  )

  (symbol (lib_id "antmicropower:GND") (at 97.79 198.12 0) (unit 1)
    (in_bom yes) (on_board yes) (dnp no)
    (property "Reference" "#PWR0110" (at 97.79 204.47 0)
      (effects (font (size 1.27 1.27)) hide)
    )
    (property "Value" "GND" (at 97.917 202.5142 0)
      (effects (font (size 1.27 1.27)))
    )
    (property "Footprint" "" (at 97.79 198.12 0)
      (effects (font (size 1.27 1.27)) hide)
    )
    (property "Datasheet" "" (at 97.79 198.12 0)
      (effects (font (size 1.27 1.27)) hide)
    )
    (property "Author" "Antmicro" (at 106.68 205.74 0)
      (effects (font (size 1.27 1.27) (thickness 0.15)) (justify left bottom) hide)
    )
    (property "License" "Apache-2.0" (at 106.68 208.28 0)
      (effects (font (size 1.27 1.27) (thickness 0.15)) (justify left bottom) hide)
    )
    (pin "1")
    (instances
      (project "ecp5-dc-scm"
        (path ""
          (reference "#PWR0110") (unit 1)
        )
      )
    )
  )

  (symbol (lib_id "antmicroCapacitors0402:C_470n_0402") (at 171.45 191.77 90) (mirror x) (unit 1)
    (in_bom yes) (on_board yes) (dnp no) (fields_autoplaced)
    (property "Reference" "C220" (at 173.99 193.0463 90)
      (effects (font (size 1.524 1.524)) (justify right))
    )
    (property "Value" "C_470n_0402" (at 175.26 191.77 0)
      (effects (font (size 1.524 1.524)) hide)
    )
    (property "Footprint" "antmicro-footprints:C_0402_1005Metric" (at 166.37 196.85 0)
      (effects (font (size 1.524 1.524)) (justify left) hide)
    )
    (property "Datasheet" "https://product.tdk.com/en/search/capacitor/ceramic/mlcc/info?part_no=C1005X5R1E474M050BB" (at 171.45 191.77 0)
      (effects (font (size 1.27 1.27)) hide)
    )
    (property "Manufacturer" "TDK" (at 161.29 196.85 0)
      (effects (font (size 1.524 1.524)) (justify left) hide)
    )
    (property "MPN" "C1005X5R1E474M050BB" (at 163.83 196.85 0)
      (effects (font (size 1.524 1.524)) (justify left) hide)
    )
    (property "Val" "470n" (at 173.99 195.5863 90)
      (effects (font (size 1.27 1.27)) (justify right))
    )
    (property "License" "Apache-2.0" (at 194.31 212.09 0)
      (effects (font (size 1.27 1.27) (thickness 0.15)) (justify left bottom) hide)
    )
    (property "Author" "Antmicro" (at 196.85 212.09 0)
      (effects (font (size 1.27 1.27) (thickness 0.15)) (justify left bottom) hide)
    )
    (property "Voltage" "" (at 199.39 212.09 0)
      (effects (font (size 1.27 1.27)) (justify left bottom) hide)
    )
    (property "Dielectric" "" (at 201.93 212.09 0)
      (effects (font (size 1.27 1.27)) (justify left bottom) hide)
    )
    (property "Public" "False" (at 204.47 212.09 0)
      (effects (font (size 1.27 1.27)) (justify left bottom) hide)
    )
    (pin "1")
    (pin "2")
    (instances
      (project "ecp5-dc-scm"
        (path ""
          (reference "C220") (unit 1)
        )
      )
    )
  )

  (symbol (lib_id "antmicroCapacitors0402:C_470n_0402") (at 157.48 191.77 90) (mirror x) (unit 1)
    (in_bom yes) (on_board yes) (dnp no) (fields_autoplaced)
    (property "Reference" "C218" (at 159.893 193.0463 90)
      (effects (font (size 1.524 1.524)) (justify right))
    )
    (property "Value" "C_470n_0402" (at 161.29 191.77 0)
      (effects (font (size 1.524 1.524)) hide)
    )
    (property "Footprint" "antmicro-footprints:C_0402_1005Metric" (at 152.4 196.85 0)
      (effects (font (size 1.524 1.524)) (justify left) hide)
    )
    (property "Datasheet" "https://product.tdk.com/en/search/capacitor/ceramic/mlcc/info?part_no=C1005X5R1E474M050BB" (at 157.48 191.77 0)
      (effects (font (size 1.27 1.27)) hide)
    )
    (property "Manufacturer" "TDK" (at 147.32 196.85 0)
      (effects (font (size 1.524 1.524)) (justify left) hide)
    )
    (property "MPN" "C1005X5R1E474M050BB" (at 149.86 196.85 0)
      (effects (font (size 1.524 1.524)) (justify left) hide)
    )
    (property "Val" "470n" (at 159.893 195.5863 90)
      (effects (font (size 1.27 1.27)) (justify right))
    )
    (property "License" "Apache-2.0" (at 180.34 212.09 0)
      (effects (font (size 1.27 1.27) (thickness 0.15)) (justify left bottom) hide)
    )
    (property "Author" "Antmicro" (at 182.88 212.09 0)
      (effects (font (size 1.27 1.27) (thickness 0.15)) (justify left bottom) hide)
    )
    (property "Voltage" "" (at 185.42 212.09 0)
      (effects (font (size 1.27 1.27)) (justify left bottom) hide)
    )
    (property "Dielectric" "" (at 187.96 212.09 0)
      (effects (font (size 1.27 1.27)) (justify left bottom) hide)
    )
    (property "Public" "False" (at 190.5 212.09 0)
      (effects (font (size 1.27 1.27)) (justify left bottom) hide)
    )
    (pin "1")
    (pin "2")
    (instances
      (project "ecp5-dc-scm"
        (path ""
          (reference "C218") (unit 1)
        )
      )
    )
  )

  (symbol (lib_id "antmicroFPGAChips:ECP5_LFE5UM5G-85") (at 209.55 232.41 0) (unit 10)
    (in_bom yes) (on_board yes) (dnp no)
    (property "Reference" "U21" (at 223.012 234.8738 0)
      (effects (font (size 1.524 1.524)) (justify left))
    )
    (property "Value" "ECP5UM5G_85_CABGA756" (at 223.012 237.5662 0)
      (effects (font (size 1.524 1.524)) (justify left))
    )
    (property "Footprint" "antmicro-footprints:BGA-1024-756_27x27mm_Layout32x32_P0.8mm" (at 198.12 172.72 90)
      (effects (font (size 1.27 1.27)) hide)
    )
    (property "Datasheet" "https://www.latticesemi.com/-/media/LatticeSemi/Documents/DataSheets/ECP5/FPGA-DS-02012-2-2-ECP5-ECP5G-Family-Data-Sheet.ashx?document_id=50461" (at 198.12 172.72 90)
      (effects (font (size 1.27 1.27)) hide)
    )
    (property "MPN" "LFE5UM5G-85F-8BG756C" (at 196.85 176.53 90)
      (effects (font (size 1.524 1.524)) (justify right) hide)
    )
    (property "Manufacturer" "Lattice Semiconductor" (at 198.12 172.72 90)
      (effects (font (size 1.27 1.27)) hide)
    )
    (property "Author" "Antmicro" (at 287.02 251.46 0)
      (effects (font (size 1.27 1.27) (thickness 0.15)) (justify left bottom) hide)
    )
    (property "License" "Apache-2.0" (at 287.02 254 0)
      (effects (font (size 1.27 1.27) (thickness 0.15)) (justify left bottom) hide)
    )
    (pin "AA11")
    (pin "AA12")
    (pin "AA13")
    (pin "AA14")
    (pin "AA15")
    (pin "AA16")
    (pin "AA17")
    (pin "AA18")
    (pin "AA19")
    (pin "AA20")
    (pin "AA21")
    (pin "AA22")
    (pin "AB11")
    (pin "AB12")
    (pin "AB13")
    (pin "AB14")
    (pin "AB15")
    (pin "AB16")
    (pin "AB17")
    (pin "AB18")
    (pin "AB19")
    (pin "AB20")
    (pin "AB21")
    (pin "AB22")
    (pin "AC11")
    (pin "AC12")
    (pin "AC13")
    (pin "AC14")
    (pin "AC15")
    (pin "AC16")
    (pin "AC17")
    (pin "AC18")
    (pin "AC19")
    (pin "AC20")
    (pin "AC21")
    (pin "AC22")
    (pin "AC29")
    (pin "AC4")
    (pin "AD2")
    (pin "AD28")
    (pin "AD31")
    (pin "AD5")
    (pin "AE26")
    (pin "AE7")
    (pin "AF11")
    (pin "AF12")
    (pin "AF14")
    (pin "AF15")
    (pin "AF16")
    (pin "AF17")
    (pin "AF19")
    (pin "AF20")
    (pin "AF22")
    (pin "AF23")
    (pin "AG11")
    (pin "AG12")
    (pin "AG14")
    (pin "AG15")
    (pin "AG16")
    (pin "AG17")
    (pin "AG19")
    (pin "AG2")
    (pin "AG20")
    (pin "AG22")
    (pin "AG23")
    (pin "AG24")
    (pin "AG31")
    (pin "AG9")
    (pin "AH11")
    (pin "AH12")
    (pin "AH14")
    (pin "AH15")
    (pin "AH16")
    (pin "AH17")
    (pin "AH19")
    (pin "AH2")
    (pin "AH20")
    (pin "AH22")
    (pin "AH23")
    (pin "AH24")
    (pin "AH25")
    (pin "AH26")
    (pin "AH29")
    (pin "AH31")
    (pin "AH5")
    (pin "AH7")
    (pin "AH8")
    (pin "AH9")
    (pin "AJ10")
    (pin "AJ11")
    (pin "AJ12")
    (pin "AJ13")
    (pin "AJ14")
    (pin "AJ15")
    (pin "AJ16")
    (pin "AJ17")
    (pin "AJ18")
    (pin "AJ19")
    (pin "AJ20")
    (pin "AJ21")
    (pin "AJ22")
    (pin "AJ23")
    (pin "AJ24")
    (pin "AJ25")
    (pin "AJ26")
    (pin "AJ7")
    (pin "AJ8")
    (pin "AJ9")
    (pin "AK11")
    (pin "AK14")
    (pin "AK15")
    (pin "AK16")
    (pin "AK17")
    (pin "AK20")
    (pin "AK23")
    (pin "AK24")
    (pin "AK25")
    (pin "AK26")
    (pin "AK7")
    (pin "AK8")
    (pin "AL11")
    (pin "AL12")
    (pin "AL14")
    (pin "AL15")
    (pin "AL17")
    (pin "AL18")
    (pin "AL2")
    (pin "AL20")
    (pin "AL21")
    (pin "AL23")
    (pin "AL24")
    (pin "AL26")
    (pin "AL29")
    (pin "AL31")
    (pin "AL5")
    (pin "AL7")
    (pin "AL8")
    (pin "AL9")
    (pin "AM26")
    (pin "AM7")
    (pin "B13")
    (pin "B15")
    (pin "B18")
    (pin "B2")
    (pin "B20")
    (pin "B24")
    (pin "B28")
    (pin "B31")
    (pin "B5")
    (pin "B9")
    (pin "E13")
    (pin "E15")
    (pin "E18")
    (pin "E2")
    (pin "E20")
    (pin "E24")
    (pin "E26")
    (pin "E28")
    (pin "E31")
    (pin "E5")
    (pin "E7")
    (pin "E9")
    (pin "G10")
    (pin "G11")
    (pin "G14")
    (pin "G15")
    (pin "G16")
    (pin "G17")
    (pin "G18")
    (pin "G19")
    (pin "G22")
    (pin "G23")
    (pin "G24")
    (pin "G9")
    (pin "H29")
    (pin "H4")
    (pin "J2")
    (pin "J28")
    (pin "J31")
    (pin "J5")
    (pin "K10")
    (pin "K11")
    (pin "K13")
    (pin "K20")
    (pin "K22")
    (pin "K23")
    (pin "L10")
    (pin "L11")
    (pin "L12")
    (pin "L13")
    (pin "L14")
    (pin "L15")
    (pin "L16")
    (pin "L17")
    (pin "L18")
    (pin "L19")
    (pin "L20")
    (pin "L21")
    (pin "L22")
    (pin "L23")
    (pin "L28")
    (pin "L5")
    (pin "M11")
    (pin "M12")
    (pin "M13")
    (pin "M14")
    (pin "M15")
    (pin "M16")
    (pin "M17")
    (pin "M18")
    (pin "M19")
    (pin "M20")
    (pin "M21")
    (pin "M22")
    (pin "N10")
    (pin "N11")
    (pin "N12")
    (pin "N13")
    (pin "N14")
    (pin "N15")
    (pin "N16")
    (pin "N17")
    (pin "N18")
    (pin "N19")
    (pin "N2")
    (pin "N20")
    (pin "N21")
    (pin "N22")
    (pin "N23")
    (pin "N28")
    (pin "N31")
    (pin "N5")
    (pin "P11")
    (pin "P12")
    (pin "P13")
    (pin "P14")
    (pin "P15")
    (pin "P16")
    (pin "P17")
    (pin "P18")
    (pin "P19")
    (pin "P20")
    (pin "P21")
    (pin "P22")
    (pin "R11")
    (pin "R12")
    (pin "R13")
    (pin "R14")
    (pin "R15")
    (pin "R16")
    (pin "R17")
    (pin "R18")
    (pin "R19")
    (pin "R2")
    (pin "R20")
    (pin "R21")
    (pin "R22")
    (pin "R28")
    (pin "R31")
    (pin "R5")
    (pin "T11")
    (pin "T12")
    (pin "T13")
    (pin "T14")
    (pin "T15")
    (pin "T16")
    (pin "T17")
    (pin "T18")
    (pin "T19")
    (pin "T20")
    (pin "T21")
    (pin "T22")
    (pin "U11")
    (pin "U12")
    (pin "U13")
    (pin "U14")
    (pin "U15")
    (pin "U16")
    (pin "U17")
    (pin "U18")
    (pin "U19")
    (pin "U20")
    (pin "U21")
    (pin "U22")
    (pin "V11")
    (pin "V12")
    (pin "V13")
    (pin "V14")
    (pin "V15")
    (pin "V16")
    (pin "V17")
    (pin "V18")
    (pin "V19")
    (pin "V2")
    (pin "V20")
    (pin "V21")
    (pin "V22")
    (pin "V28")
    (pin "V3")
    (pin "V30")
    (pin "V31")
    (pin "V5")
    (pin "W11")
    (pin "W12")
    (pin "W13")
    (pin "W14")
    (pin "W15")
    (pin "W16")
    (pin "W17")
    (pin "W18")
    (pin "W19")
    (pin "W20")
    (pin "W21")
    (pin "W22")
    (pin "W27")
    (pin "W6")
    (pin "Y10")
    (pin "Y11")
    (pin "Y12")
    (pin "Y13")
    (pin "Y14")
    (pin "Y15")
    (pin "Y16")
    (pin "Y17")
    (pin "Y18")
    (pin "Y19")
    (pin "Y2")
    (pin "Y20")
    (pin "Y21")
    (pin "Y22")
    (pin "Y23")
    (pin "Y31")
    (pin "A10")
    (pin "A11")
    (pin "A13")
    (pin "A14")
    (pin "A15")
    (pin "A16")
    (pin "A17")
    (pin "A2")
    (pin "A3")
    (pin "A4")
    (pin "A5")
    (pin "A7")
    (pin "A8")
    (pin "A9")
    (pin "B10")
    (pin "B11")
    (pin "B14")
    (pin "B16")
    (pin "B17")
    (pin "B3")
    (pin "B4")
    (pin "B7")
    (pin "B8")
    (pin "C10")
    (pin "C11")
    (pin "C13")
    (pin "C14")
    (pin "C15")
    (pin "C16")
    (pin "C17")
    (pin "C7")
    (pin "C8")
    (pin "C9")
    (pin "D10")
    (pin "D11")
    (pin "D13")
    (pin "D14")
    (pin "D15")
    (pin "D16")
    (pin "D17")
    (pin "D7")
    (pin "D8")
    (pin "D9")
    (pin "E10")
    (pin "E11")
    (pin "E14")
    (pin "E16")
    (pin "E8")
    (pin "F10")
    (pin "F11")
    (pin "F13")
    (pin "F14")
    (pin "F15")
    (pin "F16")
    (pin "F8")
    (pin "F9")
    (pin "K12")
    (pin "K14")
    (pin "K15")
    (pin "K16")
    (pin "A18")
    (pin "A19")
    (pin "A20")
    (pin "A22")
    (pin "A23")
    (pin "A24")
    (pin "A25")
    (pin "A26")
    (pin "A28")
    (pin "A29")
    (pin "A30")
    (pin "A31")
    (pin "B19")
    (pin "B22")
    (pin "B23")
    (pin "B25")
    (pin "B26")
    (pin "B29")
    (pin "B30")
    (pin "C18")
    (pin "C19")
    (pin "C20")
    (pin "C22")
    (pin "C23")
    (pin "C24")
    (pin "C25")
    (pin "C26")
    (pin "D18")
    (pin "D19")
    (pin "D20")
    (pin "D22")
    (pin "D23")
    (pin "D24")
    (pin "D25")
    (pin "D26")
    (pin "E17")
    (pin "E19")
    (pin "E22")
    (pin "E23")
    (pin "E25")
    (pin "F17")
    (pin "F18")
    (pin "F19")
    (pin "F20")
    (pin "F22")
    (pin "F23")
    (pin "F24")
    (pin "F25")
    (pin "K17")
    (pin "K18")
    (pin "K19")
    (pin "K21")
    (pin "B32")
    (pin "C28")
    (pin "C29")
    (pin "C30")
    (pin "C31")
    (pin "C32")
    (pin "D28")
    (pin "D29")
    (pin "D30")
    (pin "D31")
    (pin "D32")
    (pin "E29")
    (pin "E30")
    (pin "E32")
    (pin "F28")
    (pin "F29")
    (pin "F30")
    (pin "F31")
    (pin "F32")
    (pin "H27")
    (pin "H28")
    (pin "H30")
    (pin "H31")
    (pin "H32")
    (pin "J26")
    (pin "J27")
    (pin "J29")
    (pin "J30")
    (pin "J32")
    (pin "K26")
    (pin "K27")
    (pin "K28")
    (pin "K29")
    (pin "K30")
    (pin "K31")
    (pin "K32")
    (pin "L26")
    (pin "L27")
    (pin "L29")
    (pin "L30")
    (pin "L31")
    (pin "L32")
    (pin "M23")
    (pin "N26")
    (pin "N27")
    (pin "N29")
    (pin "N30")
    (pin "P23")
    (pin "P26")
    (pin "P27")
    (pin "R23")
    (pin "T23")
    (pin "AA23")
    (pin "AB26")
    (pin "AB27")
    (pin "AB28")
    (pin "AB29")
    (pin "AB30")
    (pin "AB31")
    (pin "AB32")
    (pin "AC26")
    (pin "AC27")
    (pin "AC28")
    (pin "AC30")
    (pin "AC31")
    (pin "AC32")
    (pin "AD26")
    (pin "AD27")
    (pin "AD29")
    (pin "AD30")
    (pin "AD32")
    (pin "AE27")
    (pin "AE28")
    (pin "AE29")
    (pin "AE30")
    (pin "AE31")
    (pin "AE32")
    (pin "N32")
    (pin "P28")
    (pin "P29")
    (pin "P30")
    (pin "P31")
    (pin "P32")
    (pin "R26")
    (pin "R27")
    (pin "R29")
    (pin "R30")
    (pin "R32")
    (pin "T26")
    (pin "T27")
    (pin "T28")
    (pin "T29")
    (pin "T30")
    (pin "T31")
    (pin "T32")
    (pin "U23")
    (pin "U26")
    (pin "U27")
    (pin "U28")
    (pin "U29")
    (pin "U30")
    (pin "U31")
    (pin "U32")
    (pin "V23")
    (pin "V26")
    (pin "V27")
    (pin "V29")
    (pin "V32")
    (pin "W23")
    (pin "W28")
    (pin "W29")
    (pin "W30")
    (pin "W31")
    (pin "W32")
    (pin "Y26")
    (pin "Y27")
    (pin "Y28")
    (pin "Y29")
    (pin "Y30")
    (pin "Y32")
    (pin "AB23")
    (pin "AC23")
    (pin "AG28")
    (pin "AG29")
    (pin "AG30")
    (pin "AG32")
    (pin "AH28")
    (pin "AH30")
    (pin "AH32")
    (pin "AJ28")
    (pin "AJ29")
    (pin "AJ30")
    (pin "AJ31")
    (pin "AJ32")
    (pin "AK28")
    (pin "AK29")
    (pin "AK30")
    (pin "AK31")
    (pin "AK32")
    (pin "AL28")
    (pin "AL30")
    (pin "AL32")
    (pin "AM28")
    (pin "AM29")
    (pin "AM30")
    (pin "AM31")
    (pin "AA10")
    (pin "AB1")
    (pin "AB2")
    (pin "AB3")
    (pin "AB4")
    (pin "AB5")
    (pin "AB6")
    (pin "AB7")
    (pin "AC1")
    (pin "AC2")
    (pin "AC3")
    (pin "AC5")
    (pin "AC6")
    (pin "AC7")
    (pin "AD1")
    (pin "AD3")
    (pin "AD4")
    (pin "AD6")
    (pin "AD7")
    (pin "AE1")
    (pin "AE2")
    (pin "AE3")
    (pin "AE4")
    (pin "AE5")
    (pin "AE6")
    (pin "N1")
    (pin "P1")
    (pin "P2")
    (pin "P3")
    (pin "P4")
    (pin "P5")
    (pin "R1")
    (pin "R3")
    (pin "R4")
    (pin "R6")
    (pin "R7")
    (pin "T1")
    (pin "T2")
    (pin "T3")
    (pin "T4")
    (pin "T5")
    (pin "T6")
    (pin "T7")
    (pin "U1")
    (pin "U10")
    (pin "U2")
    (pin "U3")
    (pin "U4")
    (pin "U5")
    (pin "U6")
    (pin "U7")
    (pin "V1")
    (pin "V10")
    (pin "V4")
    (pin "V6")
    (pin "V7")
    (pin "W1")
    (pin "W10")
    (pin "W2")
    (pin "W3")
    (pin "W4")
    (pin "W5")
    (pin "Y1")
    (pin "Y3")
    (pin "Y4")
    (pin "Y5")
    (pin "Y6")
    (pin "Y7")
    (pin "B1")
    (pin "C1")
    (pin "C2")
    (pin "C3")
    (pin "C4")
    (pin "C5")
    (pin "D1")
    (pin "D2")
    (pin "D3")
    (pin "D4")
    (pin "D5")
    (pin "E1")
    (pin "E3")
    (pin "E4")
    (pin "F1")
    (pin "F2")
    (pin "F3")
    (pin "F4")
    (pin "F5")
    (pin "H1")
    (pin "H2")
    (pin "H3")
    (pin "H5")
    (pin "H6")
    (pin "J1")
    (pin "J3")
    (pin "J4")
    (pin "J6")
    (pin "J7")
    (pin "K1")
    (pin "K2")
    (pin "K3")
    (pin "K4")
    (pin "K5")
    (pin "K6")
    (pin "K7")
    (pin "L1")
    (pin "L2")
    (pin "L3")
    (pin "L4")
    (pin "L6")
    (pin "L7")
    (pin "M10")
    (pin "N3")
    (pin "N4")
    (pin "N6")
    (pin "N7")
    (pin "P10")
    (pin "P6")
    (pin "P7")
    (pin "R10")
    (pin "T10")
    (pin "AB10")
    (pin "AC10")
    (pin "AG1")
    (pin "AG3")
    (pin "AG4")
    (pin "AH1")
    (pin "AH3")
    (pin "AH4")
    (pin "AJ1")
    (pin "AJ2")
    (pin "AJ3")
    (pin "AJ4")
    (pin "AK1")
    (pin "AK2")
    (pin "AK3")
    (pin "AK4")
    (pin "AL1")
    (pin "AL3")
    (pin "AL4")
    (pin "AM2")
    (pin "AM3")
    (pin "AM4")
    (pin "AG5")
    (pin "AJ5")
    (pin "AK5")
    (pin "AM5")
    (pin "AK10")
    (pin "AK12")
    (pin "AK13")
    (pin "AK9")
    (pin "AM11")
    (pin "AM12")
    (pin "AM14")
    (pin "AM15")
    (pin "AM8")
    (pin "AM9")
    (pin "AK18")
    (pin "AK19")
    (pin "AK21")
    (pin "AK22")
    (pin "AM17")
    (pin "AM18")
    (pin "AM20")
    (pin "AM21")
    (pin "AM23")
    (pin "AM24")
    (instances
      (project "ecp5-dc-scm"
        (path ""
          (reference "U21") (unit 10)
        )
      )
    )
  )

  (symbol (lib_id "antmicroFPGAChips:ECP5_LFE5UM5G-85") (at 236.22 255.27 0) (unit 11)
    (in_bom yes) (on_board yes) (dnp no)
    (property "Reference" "U21" (at 259.842 265.3538 0)
      (effects (font (size 1.524 1.524)) (justify left))
    )
    (property "Value" "ECP5UM5G_85_CABGA756" (at 259.842 268.0462 0)
      (effects (font (size 1.524 1.524)) (justify left))
    )
    (property "Footprint" "antmicro-footprints:BGA-1024-756_27x27mm_Layout32x32_P0.8mm" (at 224.79 195.58 90)
      (effects (font (size 1.27 1.27)) hide)
    )
    (property "Datasheet" "https://www.latticesemi.com/-/media/LatticeSemi/Documents/DataSheets/ECP5/FPGA-DS-02012-2-2-ECP5-ECP5G-Family-Data-Sheet.ashx?document_id=50461" (at 224.79 195.58 90)
      (effects (font (size 1.27 1.27)) hide)
    )
    (property "MPN" "LFE5UM5G-85F-8BG756C" (at 223.52 199.39 90)
      (effects (font (size 1.524 1.524)) (justify right) hide)
    )
    (property "Manufacturer" "Lattice Semiconductor" (at 224.79 195.58 90)
      (effects (font (size 1.27 1.27)) hide)
    )
    (property "Author" "Antmicro" (at 313.69 274.32 0)
      (effects (font (size 1.27 1.27) (thickness 0.15)) (justify left bottom) hide)
    )
    (property "License" "Apache-2.0" (at 313.69 276.86 0)
      (effects (font (size 1.27 1.27) (thickness 0.15)) (justify left bottom) hide)
    )
    (pin "AA11")
    (pin "AA12")
    (pin "AA13")
    (pin "AA14")
    (pin "AA15")
    (pin "AA16")
    (pin "AA17")
    (pin "AA18")
    (pin "AA19")
    (pin "AA20")
    (pin "AA21")
    (pin "AA22")
    (pin "AB11")
    (pin "AB12")
    (pin "AB13")
    (pin "AB14")
    (pin "AB15")
    (pin "AB16")
    (pin "AB17")
    (pin "AB18")
    (pin "AB19")
    (pin "AB20")
    (pin "AB21")
    (pin "AB22")
    (pin "AC11")
    (pin "AC12")
    (pin "AC13")
    (pin "AC14")
    (pin "AC15")
    (pin "AC16")
    (pin "AC17")
    (pin "AC18")
    (pin "AC19")
    (pin "AC20")
    (pin "AC21")
    (pin "AC22")
    (pin "AC29")
    (pin "AC4")
    (pin "AD2")
    (pin "AD28")
    (pin "AD31")
    (pin "AD5")
    (pin "AE26")
    (pin "AE7")
    (pin "AF11")
    (pin "AF12")
    (pin "AF14")
    (pin "AF15")
    (pin "AF16")
    (pin "AF17")
    (pin "AF19")
    (pin "AF20")
    (pin "AF22")
    (pin "AF23")
    (pin "AG11")
    (pin "AG12")
    (pin "AG14")
    (pin "AG15")
    (pin "AG16")
    (pin "AG17")
    (pin "AG19")
    (pin "AG2")
    (pin "AG20")
    (pin "AG22")
    (pin "AG23")
    (pin "AG24")
    (pin "AG31")
    (pin "AG9")
    (pin "AH11")
    (pin "AH12")
    (pin "AH14")
    (pin "AH15")
    (pin "AH16")
    (pin "AH17")
    (pin "AH19")
    (pin "AH2")
    (pin "AH20")
    (pin "AH22")
    (pin "AH23")
    (pin "AH24")
    (pin "AH25")
    (pin "AH26")
    (pin "AH29")
    (pin "AH31")
    (pin "AH5")
    (pin "AH7")
    (pin "AH8")
    (pin "AH9")
    (pin "AJ10")
    (pin "AJ11")
    (pin "AJ12")
    (pin "AJ13")
    (pin "AJ14")
    (pin "AJ15")
    (pin "AJ16")
    (pin "AJ17")
    (pin "AJ18")
    (pin "AJ19")
    (pin "AJ20")
    (pin "AJ21")
    (pin "AJ22")
    (pin "AJ23")
    (pin "AJ24")
    (pin "AJ25")
    (pin "AJ26")
    (pin "AJ7")
    (pin "AJ8")
    (pin "AJ9")
    (pin "AK11")
    (pin "AK14")
    (pin "AK15")
    (pin "AK16")
    (pin "AK17")
    (pin "AK20")
    (pin "AK23")
    (pin "AK24")
    (pin "AK25")
    (pin "AK26")
    (pin "AK7")
    (pin "AK8")
    (pin "AL11")
    (pin "AL12")
    (pin "AL14")
    (pin "AL15")
    (pin "AL17")
    (pin "AL18")
    (pin "AL2")
    (pin "AL20")
    (pin "AL21")
    (pin "AL23")
    (pin "AL24")
    (pin "AL26")
    (pin "AL29")
    (pin "AL31")
    (pin "AL5")
    (pin "AL7")
    (pin "AL8")
    (pin "AL9")
    (pin "AM26")
    (pin "AM7")
    (pin "B13")
    (pin "B15")
    (pin "B18")
    (pin "B2")
    (pin "B20")
    (pin "B24")
    (pin "B28")
    (pin "B31")
    (pin "B5")
    (pin "B9")
    (pin "E13")
    (pin "E15")
    (pin "E18")
    (pin "E2")
    (pin "E20")
    (pin "E24")
    (pin "E26")
    (pin "E28")
    (pin "E31")
    (pin "E5")
    (pin "E7")
    (pin "E9")
    (pin "G10")
    (pin "G11")
    (pin "G14")
    (pin "G15")
    (pin "G16")
    (pin "G17")
    (pin "G18")
    (pin "G19")
    (pin "G22")
    (pin "G23")
    (pin "G24")
    (pin "G9")
    (pin "H29")
    (pin "H4")
    (pin "J2")
    (pin "J28")
    (pin "J31")
    (pin "J5")
    (pin "K10")
    (pin "K11")
    (pin "K13")
    (pin "K20")
    (pin "K22")
    (pin "K23")
    (pin "L10")
    (pin "L11")
    (pin "L12")
    (pin "L13")
    (pin "L14")
    (pin "L15")
    (pin "L16")
    (pin "L17")
    (pin "L18")
    (pin "L19")
    (pin "L20")
    (pin "L21")
    (pin "L22")
    (pin "L23")
    (pin "L28")
    (pin "L5")
    (pin "M11")
    (pin "M12")
    (pin "M13")
    (pin "M14")
    (pin "M15")
    (pin "M16")
    (pin "M17")
    (pin "M18")
    (pin "M19")
    (pin "M20")
    (pin "M21")
    (pin "M22")
    (pin "N10")
    (pin "N11")
    (pin "N12")
    (pin "N13")
    (pin "N14")
    (pin "N15")
    (pin "N16")
    (pin "N17")
    (pin "N18")
    (pin "N19")
    (pin "N2")
    (pin "N20")
    (pin "N21")
    (pin "N22")
    (pin "N23")
    (pin "N28")
    (pin "N31")
    (pin "N5")
    (pin "P11")
    (pin "P12")
    (pin "P13")
    (pin "P14")
    (pin "P15")
    (pin "P16")
    (pin "P17")
    (pin "P18")
    (pin "P19")
    (pin "P20")
    (pin "P21")
    (pin "P22")
    (pin "R11")
    (pin "R12")
    (pin "R13")
    (pin "R14")
    (pin "R15")
    (pin "R16")
    (pin "R17")
    (pin "R18")
    (pin "R19")
    (pin "R2")
    (pin "R20")
    (pin "R21")
    (pin "R22")
    (pin "R28")
    (pin "R31")
    (pin "R5")
    (pin "T11")
    (pin "T12")
    (pin "T13")
    (pin "T14")
    (pin "T15")
    (pin "T16")
    (pin "T17")
    (pin "T18")
    (pin "T19")
    (pin "T20")
    (pin "T21")
    (pin "T22")
    (pin "U11")
    (pin "U12")
    (pin "U13")
    (pin "U14")
    (pin "U15")
    (pin "U16")
    (pin "U17")
    (pin "U18")
    (pin "U19")
    (pin "U20")
    (pin "U21")
    (pin "U22")
    (pin "V11")
    (pin "V12")
    (pin "V13")
    (pin "V14")
    (pin "V15")
    (pin "V16")
    (pin "V17")
    (pin "V18")
    (pin "V19")
    (pin "V2")
    (pin "V20")
    (pin "V21")
    (pin "V22")
    (pin "V28")
    (pin "V3")
    (pin "V30")
    (pin "V31")
    (pin "V5")
    (pin "W11")
    (pin "W12")
    (pin "W13")
    (pin "W14")
    (pin "W15")
    (pin "W16")
    (pin "W17")
    (pin "W18")
    (pin "W19")
    (pin "W20")
    (pin "W21")
    (pin "W22")
    (pin "W27")
    (pin "W6")
    (pin "Y10")
    (pin "Y11")
    (pin "Y12")
    (pin "Y13")
    (pin "Y14")
    (pin "Y15")
    (pin "Y16")
    (pin "Y17")
    (pin "Y18")
    (pin "Y19")
    (pin "Y2")
    (pin "Y20")
    (pin "Y21")
    (pin "Y22")
    (pin "Y23")
    (pin "Y31")
    (pin "A10")
    (pin "A11")
    (pin "A13")
    (pin "A14")
    (pin "A15")
    (pin "A16")
    (pin "A17")
    (pin "A2")
    (pin "A3")
    (pin "A4")
    (pin "A5")
    (pin "A7")
    (pin "A8")
    (pin "A9")
    (pin "B10")
    (pin "B11")
    (pin "B14")
    (pin "B16")
    (pin "B17")
    (pin "B3")
    (pin "B4")
    (pin "B7")
    (pin "B8")
    (pin "C10")
    (pin "C11")
    (pin "C13")
    (pin "C14")
    (pin "C15")
    (pin "C16")
    (pin "C17")
    (pin "C7")
    (pin "C8")
    (pin "C9")
    (pin "D10")
    (pin "D11")
    (pin "D13")
    (pin "D14")
    (pin "D15")
    (pin "D16")
    (pin "D17")
    (pin "D7")
    (pin "D8")
    (pin "D9")
    (pin "E10")
    (pin "E11")
    (pin "E14")
    (pin "E16")
    (pin "E8")
    (pin "F10")
    (pin "F11")
    (pin "F13")
    (pin "F14")
    (pin "F15")
    (pin "F16")
    (pin "F8")
    (pin "F9")
    (pin "K12")
    (pin "K14")
    (pin "K15")
    (pin "K16")
    (pin "A18")
    (pin "A19")
    (pin "A20")
    (pin "A22")
    (pin "A23")
    (pin "A24")
    (pin "A25")
    (pin "A26")
    (pin "A28")
    (pin "A29")
    (pin "A30")
    (pin "A31")
    (pin "B19")
    (pin "B22")
    (pin "B23")
    (pin "B25")
    (pin "B26")
    (pin "B29")
    (pin "B30")
    (pin "C18")
    (pin "C19")
    (pin "C20")
    (pin "C22")
    (pin "C23")
    (pin "C24")
    (pin "C25")
    (pin "C26")
    (pin "D18")
    (pin "D19")
    (pin "D20")
    (pin "D22")
    (pin "D23")
    (pin "D24")
    (pin "D25")
    (pin "D26")
    (pin "E17")
    (pin "E19")
    (pin "E22")
    (pin "E23")
    (pin "E25")
    (pin "F17")
    (pin "F18")
    (pin "F19")
    (pin "F20")
    (pin "F22")
    (pin "F23")
    (pin "F24")
    (pin "F25")
    (pin "K17")
    (pin "K18")
    (pin "K19")
    (pin "K21")
    (pin "B32")
    (pin "C28")
    (pin "C29")
    (pin "C30")
    (pin "C31")
    (pin "C32")
    (pin "D28")
    (pin "D29")
    (pin "D30")
    (pin "D31")
    (pin "D32")
    (pin "E29")
    (pin "E30")
    (pin "E32")
    (pin "F28")
    (pin "F29")
    (pin "F30")
    (pin "F31")
    (pin "F32")
    (pin "H27")
    (pin "H28")
    (pin "H30")
    (pin "H31")
    (pin "H32")
    (pin "J26")
    (pin "J27")
    (pin "J29")
    (pin "J30")
    (pin "J32")
    (pin "K26")
    (pin "K27")
    (pin "K28")
    (pin "K29")
    (pin "K30")
    (pin "K31")
    (pin "K32")
    (pin "L26")
    (pin "L27")
    (pin "L29")
    (pin "L30")
    (pin "L31")
    (pin "L32")
    (pin "M23")
    (pin "N26")
    (pin "N27")
    (pin "N29")
    (pin "N30")
    (pin "P23")
    (pin "P26")
    (pin "P27")
    (pin "R23")
    (pin "T23")
    (pin "AA23")
    (pin "AB26")
    (pin "AB27")
    (pin "AB28")
    (pin "AB29")
    (pin "AB30")
    (pin "AB31")
    (pin "AB32")
    (pin "AC26")
    (pin "AC27")
    (pin "AC28")
    (pin "AC30")
    (pin "AC31")
    (pin "AC32")
    (pin "AD26")
    (pin "AD27")
    (pin "AD29")
    (pin "AD30")
    (pin "AD32")
    (pin "AE27")
    (pin "AE28")
    (pin "AE29")
    (pin "AE30")
    (pin "AE31")
    (pin "AE32")
    (pin "N32")
    (pin "P28")
    (pin "P29")
    (pin "P30")
    (pin "P31")
    (pin "P32")
    (pin "R26")
    (pin "R27")
    (pin "R29")
    (pin "R30")
    (pin "R32")
    (pin "T26")
    (pin "T27")
    (pin "T28")
    (pin "T29")
    (pin "T30")
    (pin "T31")
    (pin "T32")
    (pin "U23")
    (pin "U26")
    (pin "U27")
    (pin "U28")
    (pin "U29")
    (pin "U30")
    (pin "U31")
    (pin "U32")
    (pin "V23")
    (pin "V26")
    (pin "V27")
    (pin "V29")
    (pin "V32")
    (pin "W23")
    (pin "W28")
    (pin "W29")
    (pin "W30")
    (pin "W31")
    (pin "W32")
    (pin "Y26")
    (pin "Y27")
    (pin "Y28")
    (pin "Y29")
    (pin "Y30")
    (pin "Y32")
    (pin "AB23")
    (pin "AC23")
    (pin "AG28")
    (pin "AG29")
    (pin "AG30")
    (pin "AG32")
    (pin "AH28")
    (pin "AH30")
    (pin "AH32")
    (pin "AJ28")
    (pin "AJ29")
    (pin "AJ30")
    (pin "AJ31")
    (pin "AJ32")
    (pin "AK28")
    (pin "AK29")
    (pin "AK30")
    (pin "AK31")
    (pin "AK32")
    (pin "AL28")
    (pin "AL30")
    (pin "AL32")
    (pin "AM28")
    (pin "AM29")
    (pin "AM30")
    (pin "AM31")
    (pin "AA10")
    (pin "AB1")
    (pin "AB2")
    (pin "AB3")
    (pin "AB4")
    (pin "AB5")
    (pin "AB6")
    (pin "AB7")
    (pin "AC1")
    (pin "AC2")
    (pin "AC3")
    (pin "AC5")
    (pin "AC6")
    (pin "AC7")
    (pin "AD1")
    (pin "AD3")
    (pin "AD4")
    (pin "AD6")
    (pin "AD7")
    (pin "AE1")
    (pin "AE2")
    (pin "AE3")
    (pin "AE4")
    (pin "AE5")
    (pin "AE6")
    (pin "N1")
    (pin "P1")
    (pin "P2")
    (pin "P3")
    (pin "P4")
    (pin "P5")
    (pin "R1")
    (pin "R3")
    (pin "R4")
    (pin "R6")
    (pin "R7")
    (pin "T1")
    (pin "T2")
    (pin "T3")
    (pin "T4")
    (pin "T5")
    (pin "T6")
    (pin "T7")
    (pin "U1")
    (pin "U10")
    (pin "U2")
    (pin "U3")
    (pin "U4")
    (pin "U5")
    (pin "U6")
    (pin "U7")
    (pin "V1")
    (pin "V10")
    (pin "V4")
    (pin "V6")
    (pin "V7")
    (pin "W1")
    (pin "W10")
    (pin "W2")
    (pin "W3")
    (pin "W4")
    (pin "W5")
    (pin "Y1")
    (pin "Y3")
    (pin "Y4")
    (pin "Y5")
    (pin "Y6")
    (pin "Y7")
    (pin "B1")
    (pin "C1")
    (pin "C2")
    (pin "C3")
    (pin "C4")
    (pin "C5")
    (pin "D1")
    (pin "D2")
    (pin "D3")
    (pin "D4")
    (pin "D5")
    (pin "E1")
    (pin "E3")
    (pin "E4")
    (pin "F1")
    (pin "F2")
    (pin "F3")
    (pin "F4")
    (pin "F5")
    (pin "H1")
    (pin "H2")
    (pin "H3")
    (pin "H5")
    (pin "H6")
    (pin "J1")
    (pin "J3")
    (pin "J4")
    (pin "J6")
    (pin "J7")
    (pin "K1")
    (pin "K2")
    (pin "K3")
    (pin "K4")
    (pin "K5")
    (pin "K6")
    (pin "K7")
    (pin "L1")
    (pin "L2")
    (pin "L3")
    (pin "L4")
    (pin "L6")
    (pin "L7")
    (pin "M10")
    (pin "N3")
    (pin "N4")
    (pin "N6")
    (pin "N7")
    (pin "P10")
    (pin "P6")
    (pin "P7")
    (pin "R10")
    (pin "T10")
    (pin "AB10")
    (pin "AC10")
    (pin "AG1")
    (pin "AG3")
    (pin "AG4")
    (pin "AH1")
    (pin "AH3")
    (pin "AH4")
    (pin "AJ1")
    (pin "AJ2")
    (pin "AJ3")
    (pin "AJ4")
    (pin "AK1")
    (pin "AK2")
    (pin "AK3")
    (pin "AK4")
    (pin "AL1")
    (pin "AL3")
    (pin "AL4")
    (pin "AM2")
    (pin "AM3")
    (pin "AM4")
    (pin "AG5")
    (pin "AJ5")
    (pin "AK5")
    (pin "AM5")
    (pin "AK10")
    (pin "AK12")
    (pin "AK13")
    (pin "AK9")
    (pin "AM11")
    (pin "AM12")
    (pin "AM14")
    (pin "AM15")
    (pin "AM8")
    (pin "AM9")
    (pin "AK18")
    (pin "AK19")
    (pin "AK21")
    (pin "AK22")
    (pin "AM17")
    (pin "AM18")
    (pin "AM20")
    (pin "AM21")
    (pin "AM23")
    (pin "AM24")
    (instances
      (project "ecp5-dc-scm"
        (path ""
          (reference "U21") (unit 11)
        )
      )
    )
  )

  (symbol (lib_id "antmicroFPGAChips:ECP5_LFE5UM5G-85") (at 266.7 236.22 0) (unit 12)
    (in_bom yes) (on_board yes) (dnp no)
    (property "Reference" "U21" (at 290.322 246.3038 0)
      (effects (font (size 1.524 1.524)) (justify left))
    )
    (property "Value" "ECP5UM5G_85_CABGA756" (at 290.322 248.9962 0)
      (effects (font (size 1.524 1.524)) (justify left))
    )
    (property "Footprint" "antmicro-footprints:BGA-1024-756_27x27mm_Layout32x32_P0.8mm" (at 255.27 176.53 90)
      (effects (font (size 1.27 1.27)) hide)
    )
    (property "Datasheet" "https://www.latticesemi.com/-/media/LatticeSemi/Documents/DataSheets/ECP5/FPGA-DS-02012-2-2-ECP5-ECP5G-Family-Data-Sheet.ashx?document_id=50461" (at 255.27 176.53 90)
      (effects (font (size 1.27 1.27)) hide)
    )
    (property "MPN" "LFE5UM5G-85F-8BG756C" (at 254 180.34 90)
      (effects (font (size 1.524 1.524)) (justify right) hide)
    )
    (property "Manufacturer" "Lattice Semiconductor" (at 255.27 176.53 90)
      (effects (font (size 1.27 1.27)) hide)
    )
    (property "Author" "Antmicro" (at 344.17 255.27 0)
      (effects (font (size 1.27 1.27) (thickness 0.15)) (justify left bottom) hide)
    )
    (property "License" "Apache-2.0" (at 344.17 257.81 0)
      (effects (font (size 1.27 1.27) (thickness 0.15)) (justify left bottom) hide)
    )
    (pin "AA11")
    (pin "AA12")
    (pin "AA13")
    (pin "AA14")
    (pin "AA15")
    (pin "AA16")
    (pin "AA17")
    (pin "AA18")
    (pin "AA19")
    (pin "AA20")
    (pin "AA21")
    (pin "AA22")
    (pin "AB11")
    (pin "AB12")
    (pin "AB13")
    (pin "AB14")
    (pin "AB15")
    (pin "AB16")
    (pin "AB17")
    (pin "AB18")
    (pin "AB19")
    (pin "AB20")
    (pin "AB21")
    (pin "AB22")
    (pin "AC11")
    (pin "AC12")
    (pin "AC13")
    (pin "AC14")
    (pin "AC15")
    (pin "AC16")
    (pin "AC17")
    (pin "AC18")
    (pin "AC19")
    (pin "AC20")
    (pin "AC21")
    (pin "AC22")
    (pin "AC29")
    (pin "AC4")
    (pin "AD2")
    (pin "AD28")
    (pin "AD31")
    (pin "AD5")
    (pin "AE26")
    (pin "AE7")
    (pin "AF11")
    (pin "AF12")
    (pin "AF14")
    (pin "AF15")
    (pin "AF16")
    (pin "AF17")
    (pin "AF19")
    (pin "AF20")
    (pin "AF22")
    (pin "AF23")
    (pin "AG11")
    (pin "AG12")
    (pin "AG14")
    (pin "AG15")
    (pin "AG16")
    (pin "AG17")
    (pin "AG19")
    (pin "AG2")
    (pin "AG20")
    (pin "AG22")
    (pin "AG23")
    (pin "AG24")
    (pin "AG31")
    (pin "AG9")
    (pin "AH11")
    (pin "AH12")
    (pin "AH14")
    (pin "AH15")
    (pin "AH16")
    (pin "AH17")
    (pin "AH19")
    (pin "AH2")
    (pin "AH20")
    (pin "AH22")
    (pin "AH23")
    (pin "AH24")
    (pin "AH25")
    (pin "AH26")
    (pin "AH29")
    (pin "AH31")
    (pin "AH5")
    (pin "AH7")
    (pin "AH8")
    (pin "AH9")
    (pin "AJ10")
    (pin "AJ11")
    (pin "AJ12")
    (pin "AJ13")
    (pin "AJ14")
    (pin "AJ15")
    (pin "AJ16")
    (pin "AJ17")
    (pin "AJ18")
    (pin "AJ19")
    (pin "AJ20")
    (pin "AJ21")
    (pin "AJ22")
    (pin "AJ23")
    (pin "AJ24")
    (pin "AJ25")
    (pin "AJ26")
    (pin "AJ7")
    (pin "AJ8")
    (pin "AJ9")
    (pin "AK11")
    (pin "AK14")
    (pin "AK15")
    (pin "AK16")
    (pin "AK17")
    (pin "AK20")
    (pin "AK23")
    (pin "AK24")
    (pin "AK25")
    (pin "AK26")
    (pin "AK7")
    (pin "AK8")
    (pin "AL11")
    (pin "AL12")
    (pin "AL14")
    (pin "AL15")
    (pin "AL17")
    (pin "AL18")
    (pin "AL2")
    (pin "AL20")
    (pin "AL21")
    (pin "AL23")
    (pin "AL24")
    (pin "AL26")
    (pin "AL29")
    (pin "AL31")
    (pin "AL5")
    (pin "AL7")
    (pin "AL8")
    (pin "AL9")
    (pin "AM26")
    (pin "AM7")
    (pin "B13")
    (pin "B15")
    (pin "B18")
    (pin "B2")
    (pin "B20")
    (pin "B24")
    (pin "B28")
    (pin "B31")
    (pin "B5")
    (pin "B9")
    (pin "E13")
    (pin "E15")
    (pin "E18")
    (pin "E2")
    (pin "E20")
    (pin "E24")
    (pin "E26")
    (pin "E28")
    (pin "E31")
    (pin "E5")
    (pin "E7")
    (pin "E9")
    (pin "G10")
    (pin "G11")
    (pin "G14")
    (pin "G15")
    (pin "G16")
    (pin "G17")
    (pin "G18")
    (pin "G19")
    (pin "G22")
    (pin "G23")
    (pin "G24")
    (pin "G9")
    (pin "H29")
    (pin "H4")
    (pin "J2")
    (pin "J28")
    (pin "J31")
    (pin "J5")
    (pin "K10")
    (pin "K11")
    (pin "K13")
    (pin "K20")
    (pin "K22")
    (pin "K23")
    (pin "L10")
    (pin "L11")
    (pin "L12")
    (pin "L13")
    (pin "L14")
    (pin "L15")
    (pin "L16")
    (pin "L17")
    (pin "L18")
    (pin "L19")
    (pin "L20")
    (pin "L21")
    (pin "L22")
    (pin "L23")
    (pin "L28")
    (pin "L5")
    (pin "M11")
    (pin "M12")
    (pin "M13")
    (pin "M14")
    (pin "M15")
    (pin "M16")
    (pin "M17")
    (pin "M18")
    (pin "M19")
    (pin "M20")
    (pin "M21")
    (pin "M22")
    (pin "N10")
    (pin "N11")
    (pin "N12")
    (pin "N13")
    (pin "N14")
    (pin "N15")
    (pin "N16")
    (pin "N17")
    (pin "N18")
    (pin "N19")
    (pin "N2")
    (pin "N20")
    (pin "N21")
    (pin "N22")
    (pin "N23")
    (pin "N28")
    (pin "N31")
    (pin "N5")
    (pin "P11")
    (pin "P12")
    (pin "P13")
    (pin "P14")
    (pin "P15")
    (pin "P16")
    (pin "P17")
    (pin "P18")
    (pin "P19")
    (pin "P20")
    (pin "P21")
    (pin "P22")
    (pin "R11")
    (pin "R12")
    (pin "R13")
    (pin "R14")
    (pin "R15")
    (pin "R16")
    (pin "R17")
    (pin "R18")
    (pin "R19")
    (pin "R2")
    (pin "R20")
    (pin "R21")
    (pin "R22")
    (pin "R28")
    (pin "R31")
    (pin "R5")
    (pin "T11")
    (pin "T12")
    (pin "T13")
    (pin "T14")
    (pin "T15")
    (pin "T16")
    (pin "T17")
    (pin "T18")
    (pin "T19")
    (pin "T20")
    (pin "T21")
    (pin "T22")
    (pin "U11")
    (pin "U12")
    (pin "U13")
    (pin "U14")
    (pin "U15")
    (pin "U16")
    (pin "U17")
    (pin "U18")
    (pin "U19")
    (pin "U20")
    (pin "U21")
    (pin "U22")
    (pin "V11")
    (pin "V12")
    (pin "V13")
    (pin "V14")
    (pin "V15")
    (pin "V16")
    (pin "V17")
    (pin "V18")
    (pin "V19")
    (pin "V2")
    (pin "V20")
    (pin "V21")
    (pin "V22")
    (pin "V28")
    (pin "V3")
    (pin "V30")
    (pin "V31")
    (pin "V5")
    (pin "W11")
    (pin "W12")
    (pin "W13")
    (pin "W14")
    (pin "W15")
    (pin "W16")
    (pin "W17")
    (pin "W18")
    (pin "W19")
    (pin "W20")
    (pin "W21")
    (pin "W22")
    (pin "W27")
    (pin "W6")
    (pin "Y10")
    (pin "Y11")
    (pin "Y12")
    (pin "Y13")
    (pin "Y14")
    (pin "Y15")
    (pin "Y16")
    (pin "Y17")
    (pin "Y18")
    (pin "Y19")
    (pin "Y2")
    (pin "Y20")
    (pin "Y21")
    (pin "Y22")
    (pin "Y23")
    (pin "Y31")
    (pin "A10")
    (pin "A11")
    (pin "A13")
    (pin "A14")
    (pin "A15")
    (pin "A16")
    (pin "A17")
    (pin "A2")
    (pin "A3")
    (pin "A4")
    (pin "A5")
    (pin "A7")
    (pin "A8")
    (pin "A9")
    (pin "B10")
    (pin "B11")
    (pin "B14")
    (pin "B16")
    (pin "B17")
    (pin "B3")
    (pin "B4")
    (pin "B7")
    (pin "B8")
    (pin "C10")
    (pin "C11")
    (pin "C13")
    (pin "C14")
    (pin "C15")
    (pin "C16")
    (pin "C17")
    (pin "C7")
    (pin "C8")
    (pin "C9")
    (pin "D10")
    (pin "D11")
    (pin "D13")
    (pin "D14")
    (pin "D15")
    (pin "D16")
    (pin "D17")
    (pin "D7")
    (pin "D8")
    (pin "D9")
    (pin "E10")
    (pin "E11")
    (pin "E14")
    (pin "E16")
    (pin "E8")
    (pin "F10")
    (pin "F11")
    (pin "F13")
    (pin "F14")
    (pin "F15")
    (pin "F16")
    (pin "F8")
    (pin "F9")
    (pin "K12")
    (pin "K14")
    (pin "K15")
    (pin "K16")
    (pin "A18")
    (pin "A19")
    (pin "A20")
    (pin "A22")
    (pin "A23")
    (pin "A24")
    (pin "A25")
    (pin "A26")
    (pin "A28")
    (pin "A29")
    (pin "A30")
    (pin "A31")
    (pin "B19")
    (pin "B22")
    (pin "B23")
    (pin "B25")
    (pin "B26")
    (pin "B29")
    (pin "B30")
    (pin "C18")
    (pin "C19")
    (pin "C20")
    (pin "C22")
    (pin "C23")
    (pin "C24")
    (pin "C25")
    (pin "C26")
    (pin "D18")
    (pin "D19")
    (pin "D20")
    (pin "D22")
    (pin "D23")
    (pin "D24")
    (pin "D25")
    (pin "D26")
    (pin "E17")
    (pin "E19")
    (pin "E22")
    (pin "E23")
    (pin "E25")
    (pin "F17")
    (pin "F18")
    (pin "F19")
    (pin "F20")
    (pin "F22")
    (pin "F23")
    (pin "F24")
    (pin "F25")
    (pin "K17")
    (pin "K18")
    (pin "K19")
    (pin "K21")
    (pin "B32")
    (pin "C28")
    (pin "C29")
    (pin "C30")
    (pin "C31")
    (pin "C32")
    (pin "D28")
    (pin "D29")
    (pin "D30")
    (pin "D31")
    (pin "D32")
    (pin "E29")
    (pin "E30")
    (pin "E32")
    (pin "F28")
    (pin "F29")
    (pin "F30")
    (pin "F31")
    (pin "F32")
    (pin "H27")
    (pin "H28")
    (pin "H30")
    (pin "H31")
    (pin "H32")
    (pin "J26")
    (pin "J27")
    (pin "J29")
    (pin "J30")
    (pin "J32")
    (pin "K26")
    (pin "K27")
    (pin "K28")
    (pin "K29")
    (pin "K30")
    (pin "K31")
    (pin "K32")
    (pin "L26")
    (pin "L27")
    (pin "L29")
    (pin "L30")
    (pin "L31")
    (pin "L32")
    (pin "M23")
    (pin "N26")
    (pin "N27")
    (pin "N29")
    (pin "N30")
    (pin "P23")
    (pin "P26")
    (pin "P27")
    (pin "R23")
    (pin "T23")
    (pin "AA23")
    (pin "AB26")
    (pin "AB27")
    (pin "AB28")
    (pin "AB29")
    (pin "AB30")
    (pin "AB31")
    (pin "AB32")
    (pin "AC26")
    (pin "AC27")
    (pin "AC28")
    (pin "AC30")
    (pin "AC31")
    (pin "AC32")
    (pin "AD26")
    (pin "AD27")
    (pin "AD29")
    (pin "AD30")
    (pin "AD32")
    (pin "AE27")
    (pin "AE28")
    (pin "AE29")
    (pin "AE30")
    (pin "AE31")
    (pin "AE32")
    (pin "N32")
    (pin "P28")
    (pin "P29")
    (pin "P30")
    (pin "P31")
    (pin "P32")
    (pin "R26")
    (pin "R27")
    (pin "R29")
    (pin "R30")
    (pin "R32")
    (pin "T26")
    (pin "T27")
    (pin "T28")
    (pin "T29")
    (pin "T30")
    (pin "T31")
    (pin "T32")
    (pin "U23")
    (pin "U26")
    (pin "U27")
    (pin "U28")
    (pin "U29")
    (pin "U30")
    (pin "U31")
    (pin "U32")
    (pin "V23")
    (pin "V26")
    (pin "V27")
    (pin "V29")
    (pin "V32")
    (pin "W23")
    (pin "W28")
    (pin "W29")
    (pin "W30")
    (pin "W31")
    (pin "W32")
    (pin "Y26")
    (pin "Y27")
    (pin "Y28")
    (pin "Y29")
    (pin "Y30")
    (pin "Y32")
    (pin "AB23")
    (pin "AC23")
    (pin "AG28")
    (pin "AG29")
    (pin "AG30")
    (pin "AG32")
    (pin "AH28")
    (pin "AH30")
    (pin "AH32")
    (pin "AJ28")
    (pin "AJ29")
    (pin "AJ30")
    (pin "AJ31")
    (pin "AJ32")
    (pin "AK28")
    (pin "AK29")
    (pin "AK30")
    (pin "AK31")
    (pin "AK32")
    (pin "AL28")
    (pin "AL30")
    (pin "AL32")
    (pin "AM28")
    (pin "AM29")
    (pin "AM30")
    (pin "AM31")
    (pin "AA10")
    (pin "AB1")
    (pin "AB2")
    (pin "AB3")
    (pin "AB4")
    (pin "AB5")
    (pin "AB6")
    (pin "AB7")
    (pin "AC1")
    (pin "AC2")
    (pin "AC3")
    (pin "AC5")
    (pin "AC6")
    (pin "AC7")
    (pin "AD1")
    (pin "AD3")
    (pin "AD4")
    (pin "AD6")
    (pin "AD7")
    (pin "AE1")
    (pin "AE2")
    (pin "AE3")
    (pin "AE4")
    (pin "AE5")
    (pin "AE6")
    (pin "N1")
    (pin "P1")
    (pin "P2")
    (pin "P3")
    (pin "P4")
    (pin "P5")
    (pin "R1")
    (pin "R3")
    (pin "R4")
    (pin "R6")
    (pin "R7")
    (pin "T1")
    (pin "T2")
    (pin "T3")
    (pin "T4")
    (pin "T5")
    (pin "T6")
    (pin "T7")
    (pin "U1")
    (pin "U10")
    (pin "U2")
    (pin "U3")
    (pin "U4")
    (pin "U5")
    (pin "U6")
    (pin "U7")
    (pin "V1")
    (pin "V10")
    (pin "V4")
    (pin "V6")
    (pin "V7")
    (pin "W1")
    (pin "W10")
    (pin "W2")
    (pin "W3")
    (pin "W4")
    (pin "W5")
    (pin "Y1")
    (pin "Y3")
    (pin "Y4")
    (pin "Y5")
    (pin "Y6")
    (pin "Y7")
    (pin "B1")
    (pin "C1")
    (pin "C2")
    (pin "C3")
    (pin "C4")
    (pin "C5")
    (pin "D1")
    (pin "D2")
    (pin "D3")
    (pin "D4")
    (pin "D5")
    (pin "E1")
    (pin "E3")
    (pin "E4")
    (pin "F1")
    (pin "F2")
    (pin "F3")
    (pin "F4")
    (pin "F5")
    (pin "H1")
    (pin "H2")
    (pin "H3")
    (pin "H5")
    (pin "H6")
    (pin "J1")
    (pin "J3")
    (pin "J4")
    (pin "J6")
    (pin "J7")
    (pin "K1")
    (pin "K2")
    (pin "K3")
    (pin "K4")
    (pin "K5")
    (pin "K6")
    (pin "K7")
    (pin "L1")
    (pin "L2")
    (pin "L3")
    (pin "L4")
    (pin "L6")
    (pin "L7")
    (pin "M10")
    (pin "N3")
    (pin "N4")
    (pin "N6")
    (pin "N7")
    (pin "P10")
    (pin "P6")
    (pin "P7")
    (pin "R10")
    (pin "T10")
    (pin "AB10")
    (pin "AC10")
    (pin "AG1")
    (pin "AG3")
    (pin "AG4")
    (pin "AH1")
    (pin "AH3")
    (pin "AH4")
    (pin "AJ1")
    (pin "AJ2")
    (pin "AJ3")
    (pin "AJ4")
    (pin "AK1")
    (pin "AK2")
    (pin "AK3")
    (pin "AK4")
    (pin "AL1")
    (pin "AL3")
    (pin "AL4")
    (pin "AM2")
    (pin "AM3")
    (pin "AM4")
    (pin "AG5")
    (pin "AJ5")
    (pin "AK5")
    (pin "AM5")
    (pin "AK10")
    (pin "AK12")
    (pin "AK13")
    (pin "AK9")
    (pin "AM11")
    (pin "AM12")
    (pin "AM14")
    (pin "AM15")
    (pin "AM8")
    (pin "AM9")
    (pin "AK18")
    (pin "AK19")
    (pin "AK21")
    (pin "AK22")
    (pin "AM17")
    (pin "AM18")
    (pin "AM20")
    (pin "AM21")
    (pin "AM23")
    (pin "AM24")
    (instances
      (project "ecp5-dc-scm"
        (path ""
          (reference "U21") (unit 12)
        )
      )
    )
  )

  (symbol (lib_id "antmicroResistors0402:R_10k_0402") (at 26.67 214.63 270) (mirror x) (unit 1)
    (in_bom yes) (on_board yes) (dnp no)
    (property "Reference" "R126" (at 24.13 210.82 90)
      (effects (font (size 1.524 1.524)) (justify right))
    )
    (property "Value" "R_10k_0402" (at 22.86 214.63 0)
      (effects (font (size 1.524 1.524)) hide)
    )
    (property "Footprint" "antmicro-footprints:R_0402_1005Metric" (at 31.75 209.55 0)
      (effects (font (size 1.524 1.524)) (justify left) hide)
    )
    (property "Datasheet" "https://www.bourns.com/docs/product-datasheets/cr.pdf" (at 26.67 214.63 0)
      (effects (font (size 1.27 1.27)) hide)
    )
    (property "Manufacturer" "Bourns" (at 36.83 209.55 0)
      (effects (font (size 1.524 1.524)) (justify left) hide)
    )
    (property "MPN" "CR0402-FX-1002GLF" (at 34.29 209.55 0)
      (effects (font (size 1.524 1.524)) (justify left) hide)
    )
    (property "Val" "10k" (at 24.13 213.36 90)
      (effects (font (size 1.27 1.27)) (justify right))
    )
    (property "License" "Apache-2.0" (at 1.27 194.31 0)
      (effects (font (size 1.27 1.27) (thickness 0.15)) (justify left bottom) hide)
    )
    (property "Author" "Antmicro" (at -1.27 194.31 0)
      (effects (font (size 1.27 1.27) (thickness 0.15)) (justify left bottom) hide)
    )
    (property "Tolerance" "1%" (at 16.51 194.31 0)
      (effects (font (size 1.27 1.27)) (justify left bottom) hide)
    )
    (property "Public" "False" (at -3.81 194.31 0)
      (effects (font (size 1.27 1.27)) (justify left bottom) hide)
    )
    (pin "1")
    (pin "2")
    (instances
      (project "ecp5-dc-scm"
        (path ""
          (reference "R126") (unit 1)
        )
      )
    )
  )

  (symbol (lib_id "antmicroResistors0402:R_22R_0402") (at 34.29 232.41 0) (mirror y) (unit 1)
    (in_bom yes) (on_board yes) (dnp no)
    (property "Reference" "R128" (at 31.75 238.76 0)
      (effects (font (size 1.524 1.524)))
    )
    (property "Value" "R_22R_0402" (at 34.29 236.22 0)
      (effects (font (size 1.524 1.524)) hide)
    )
    (property "Footprint" "antmicro-footprints:R_0402_1005Metric" (at 29.21 227.33 0)
      (effects (font (size 1.524 1.524)) (justify left) hide)
    )
    (property "Datasheet" "https://www.bourns.com/docs/product-datasheets/cr.pdf" (at 34.29 232.41 0)
      (effects (font (size 1.27 1.27)) hide)
    )
    (property "Manufacturer" "Bourns" (at 29.21 222.25 0)
      (effects (font (size 1.524 1.524)) (justify left) hide)
    )
    (property "MPN" "CR0402-FX-22R0GLF" (at 29.21 224.79 0)
      (effects (font (size 1.524 1.524)) (justify left) hide)
    )
    (property "Val" "22R" (at 31.75 236.22 0)
      (effects (font (size 1.27 1.27)))
    )
    (property "License" "Apache-2.0" (at 13.97 257.81 0)
      (effects (font (size 1.27 1.27) (thickness 0.15)) (justify left bottom) hide)
    )
    (property "Author" "Antmicro" (at 13.97 260.35 0)
      (effects (font (size 1.27 1.27) (thickness 0.15)) (justify left bottom) hide)
    )
    (property "Tolerance" "1%" (at 13.97 242.57 0)
      (effects (font (size 1.27 1.27)) (justify left bottom) hide)
    )
    (property "Public" "False" (at 13.97 262.89 0)
      (effects (font (size 1.27 1.27)) (justify left bottom) hide)
    )
    (pin "1")
    (pin "2")
    (instances
      (project "ecp5-dc-scm"
        (path ""
          (reference "R128") (unit 1)
        )
      )
    )
  )

  (symbol (lib_id "antmicroResistors0402:R_1k_0402") (at 41.91 209.55 270) (unit 1)
    (in_bom yes) (on_board yes) (dnp no) (fields_autoplaced)
    (property "Reference" "R130" (at 44.323 210.82 90)
      (effects (font (size 1.524 1.524)) (justify left))
    )
    (property "Value" "R_1k_0402" (at 38.1 209.55 0)
      (effects (font (size 1.524 1.524)) hide)
    )
    (property "Footprint" "antmicro-footprints:R_0402_1005Metric" (at 46.99 214.63 0)
      (effects (font (size 1.524 1.524)) (justify left) hide)
    )
    (property "Datasheet" "https://www.bourns.com/docs/product-datasheets/cr.pdf" (at 41.91 209.55 0)
      (effects (font (size 1.27 1.27)) hide)
    )
    (property "Manufacturer" "Bourns" (at 52.07 214.63 0)
      (effects (font (size 1.524 1.524)) (justify left) hide)
    )
    (property "MPN" "CR0402-FX-1001GLF" (at 49.53 214.63 0)
      (effects (font (size 1.524 1.524)) (justify left) hide)
    )
    (property "Val" "1k" (at 44.323 213.36 90)
      (effects (font (size 1.27 1.27)) (justify left))
    )
    (property "License" "Apache-2.0" (at 16.51 229.87 0)
      (effects (font (size 1.27 1.27) (thickness 0.15)) (justify left bottom) hide)
    )
    (property "Author" "Antmicro" (at 13.97 229.87 0)
      (effects (font (size 1.27 1.27) (thickness 0.15)) (justify left bottom) hide)
    )
    (property "Tolerance" "1%" (at 31.75 229.87 0)
      (effects (font (size 1.27 1.27)) (justify left bottom) hide)
    )
    (property "Public" "False" (at 11.43 229.87 0)
      (effects (font (size 1.27 1.27)) (justify left bottom) hide)
    )
    (pin "1")
    (pin "2")
    (instances
      (project "ecp5-dc-scm"
        (path ""
          (reference "R130") (unit 1)
        )
      )
    )
  )

  (symbol (lib_id "antmicroTransistorsFETsMOSFETsSingle:2N7002_SOT-23-3") (at 34.29 232.41 0) (unit 1)
    (in_bom yes) (on_board yes) (dnp no) (fields_autoplaced)
    (property "Reference" "Q17" (at 45.72 228.6 0)
      (effects (font (size 1.524 1.524)) (justify left))
    )
    (property "Value" "2N7002" (at 45.72 231.14 0)
      (effects (font (size 1.524 1.524)) (justify left))
    )
    (property "Footprint" "antmicro-footprints:SOT-23-3" (at 39.37 227.33 0)
      (effects (font (size 1.524 1.524)) (justify left) hide)
    )
    (property "Datasheet" "https://www.onsemi.com/pub/Collateral/NDS7002A-D.PDF" (at 39.37 224.79 0)
      (effects (font (size 1.524 1.524)) (justify left) hide)
    )
    (property "MPN" "2N7002" (at 39.37 219.71 0)
      (effects (font (size 1.524 1.524)) (justify left) hide)
    )
    (property "Manufacturer" "ON Semiconductor" (at 39.37 204.47 0)
      (effects (font (size 1.524 1.524)) (justify left) hide)
    )
    (property "Author" "Antmicro" (at 57.15 252.73 0)
      (effects (font (size 1.27 1.27) (thickness 0.15)) (justify left bottom) hide)
    )
    (property "License" "Apache-2.0" (at 57.15 255.27 0)
      (effects (font (size 1.27 1.27) (thickness 0.15)) (justify left bottom) hide)
    )
    (pin "1")
    (pin "2")
    (pin "3")
    (instances
      (project "ecp5-dc-scm"
        (path ""
          (reference "Q17") (unit 1)
        )
      )
    )
  )

  (symbol (lib_id "antmicroResistors0402:R_10k_0402") (at 25.4 255.27 90) (unit 1)
    (in_bom yes) (on_board yes) (dnp no) (fields_autoplaced)
    (property "Reference" "R127" (at 22.86 251.46 90)
      (effects (font (size 1.524 1.524)) (justify left))
    )
    (property "Value" "R_10k_0402" (at 29.21 255.27 0)
      (effects (font (size 1.524 1.524)) hide)
    )
    (property "Footprint" "antmicro-footprints:R_0402_1005Metric" (at 20.32 250.19 0)
      (effects (font (size 1.524 1.524)) (justify left) hide)
    )
    (property "Datasheet" "https://www.bourns.com/docs/product-datasheets/cr.pdf" (at 25.4 255.27 0)
      (effects (font (size 1.27 1.27)) hide)
    )
    (property "Manufacturer" "Bourns" (at 15.24 250.19 0)
      (effects (font (size 1.524 1.524)) (justify left) hide)
    )
    (property "MPN" "CR0402-FX-1002GLF" (at 17.78 250.19 0)
      (effects (font (size 1.524 1.524)) (justify left) hide)
    )
    (property "Val" "10k" (at 22.86 254 90)
      (effects (font (size 1.27 1.27)) (justify left))
    )
    (property "License" "Apache-2.0" (at 50.8 234.95 0)
      (effects (font (size 1.27 1.27) (thickness 0.15)) (justify left bottom) hide)
    )
    (property "Author" "Antmicro" (at 53.34 234.95 0)
      (effects (font (size 1.27 1.27) (thickness 0.15)) (justify left bottom) hide)
    )
    (property "Tolerance" "1%" (at 35.56 234.95 0)
      (effects (font (size 1.27 1.27)) (justify left bottom) hide)
    )
    (property "Public" "False" (at 55.88 234.95 0)
      (effects (font (size 1.27 1.27)) (justify left bottom) hide)
    )
    (pin "1")
    (pin "2")
    (instances
      (project "ecp5-dc-scm"
        (path ""
          (reference "R127") (unit 1)
        )
      )
    )
  )

  (symbol (lib_id "antmicropower:GND") (at 273.05 100.33 0) (unit 1)
    (in_bom yes) (on_board yes) (dnp no)
    (property "Reference" "#PWR0112" (at 273.05 106.68 0)
      (effects (font (size 1.27 1.27)) hide)
    )
    (property "Value" "GND" (at 273.177 104.7242 0)
      (effects (font (size 1.27 1.27)))
    )
    (property "Footprint" "" (at 273.05 100.33 0)
      (effects (font (size 1.27 1.27)) hide)
    )
    (property "Datasheet" "" (at 273.05 100.33 0)
      (effects (font (size 1.27 1.27)) hide)
    )
    (property "Author" "Antmicro" (at 281.94 107.95 0)
      (effects (font (size 1.27 1.27) (thickness 0.15)) (justify left bottom) hide)
    )
    (property "License" "Apache-2.0" (at 281.94 110.49 0)
      (effects (font (size 1.27 1.27) (thickness 0.15)) (justify left bottom) hide)
    )
    (pin "1")
    (instances
      (project "ecp5-dc-scm"
        (path ""
          (reference "#PWR0112") (unit 1)
        )
      )
    )
  )

  (symbol (lib_id "antmicropower:GND") (at 171.45 177.8 0) (unit 1)
    (in_bom yes) (on_board yes) (dnp no) (fields_autoplaced)
    (property "Reference" "#PWR0117" (at 171.45 184.15 0)
      (effects (font (size 1.27 1.27)) hide)
    )
    (property "Value" "GND" (at 169.545 179.07 0)
      (effects (font (size 1.27 1.27)) (justify right))
    )
    (property "Footprint" "" (at 171.45 177.8 0)
      (effects (font (size 1.27 1.27)) hide)
    )
    (property "Datasheet" "" (at 171.45 177.8 0)
      (effects (font (size 1.27 1.27)) hide)
    )
    (property "Author" "Antmicro" (at 180.34 185.42 0)
      (effects (font (size 1.27 1.27) (thickness 0.15)) (justify left bottom) hide)
    )
    (property "License" "Apache-2.0" (at 180.34 187.96 0)
      (effects (font (size 1.27 1.27) (thickness 0.15)) (justify left bottom) hide)
    )
    (pin "1")
    (instances
      (project "ecp5-dc-scm"
        (path ""
          (reference "#PWR0117") (unit 1)
        )
      )
    )
  )

  (symbol (lib_id "antmicropower:GND") (at 41.91 237.49 0) (unit 1)
    (in_bom yes) (on_board yes) (dnp no)
    (property "Reference" "#PWR0107" (at 41.91 243.84 0)
      (effects (font (size 1.27 1.27)) hide)
    )
    (property "Value" "GND" (at 42.037 241.8842 0)
      (effects (font (size 1.27 1.27)))
    )
    (property "Footprint" "" (at 41.91 237.49 0)
      (effects (font (size 1.27 1.27)) hide)
    )
    (property "Datasheet" "" (at 41.91 237.49 0)
      (effects (font (size 1.27 1.27)) hide)
    )
    (property "Author" "Antmicro" (at 50.8 245.11 0)
      (effects (font (size 1.27 1.27) (thickness 0.15)) (justify left bottom) hide)
    )
    (property "License" "Apache-2.0" (at 50.8 247.65 0)
      (effects (font (size 1.27 1.27) (thickness 0.15)) (justify left bottom) hide)
    )
    (pin "1")
    (instances
      (project "ecp5-dc-scm"
        (path ""
          (reference "#PWR0107") (unit 1)
        )
      )
    )
  )

  (symbol (lib_id "antmicroResistors0402:R_1k_0402") (at 27.94 250.19 270) (unit 1)
    (in_bom yes) (on_board yes) (dnp no) (fields_autoplaced)
    (property "Reference" "R129" (at 30.607 251.46 90)
      (effects (font (size 1.524 1.524)) (justify left))
    )
    (property "Value" "R_1k_0402" (at 24.13 250.19 0)
      (effects (font (size 1.524 1.524)) hide)
    )
    (property "Footprint" "antmicro-footprints:R_0402_1005Metric" (at 33.02 255.27 0)
      (effects (font (size 1.524 1.524)) (justify left) hide)
    )
    (property "Datasheet" "https://www.bourns.com/docs/product-datasheets/cr.pdf" (at 27.94 250.19 0)
      (effects (font (size 1.27 1.27)) hide)
    )
    (property "Manufacturer" "Bourns" (at 38.1 255.27 0)
      (effects (font (size 1.524 1.524)) (justify left) hide)
    )
    (property "MPN" "CR0402-FX-1001GLF" (at 35.56 255.27 0)
      (effects (font (size 1.524 1.524)) (justify left) hide)
    )
    (property "Val" "1k" (at 30.607 254 90)
      (effects (font (size 1.27 1.27)) (justify left))
    )
    (property "License" "Apache-2.0" (at 2.54 270.51 0)
      (effects (font (size 1.27 1.27) (thickness 0.15)) (justify left bottom) hide)
    )
    (property "Author" "Antmicro" (at 0 270.51 0)
      (effects (font (size 1.27 1.27) (thickness 0.15)) (justify left bottom) hide)
    )
    (property "Tolerance" "1%" (at 17.78 270.51 0)
      (effects (font (size 1.27 1.27)) (justify left bottom) hide)
    )
    (property "Public" "False" (at -2.54 270.51 0)
      (effects (font (size 1.27 1.27)) (justify left bottom) hide)
    )
    (pin "1")
    (pin "2")
    (instances
      (project "ecp5-dc-scm"
        (path ""
          (reference "R129") (unit 1)
        )
      )
    )
  )

  (symbol (lib_id "antmicroResistors0402:R_10k_0402") (at 48.26 261.62 90) (unit 1)
    (in_bom yes) (on_board yes) (dnp no) (fields_autoplaced)
    (property "Reference" "R131" (at 50.546 257.81 90)
      (effects (font (size 1.524 1.524)) (justify right))
    )
    (property "Value" "R_10k_0402" (at 52.07 261.62 0)
      (effects (font (size 1.524 1.524)) hide)
    )
    (property "Footprint" "antmicro-footprints:R_0402_1005Metric" (at 43.18 256.54 0)
      (effects (font (size 1.524 1.524)) (justify left) hide)
    )
    (property "Datasheet" "https://www.bourns.com/docs/product-datasheets/cr.pdf" (at 48.26 261.62 0)
      (effects (font (size 1.27 1.27)) hide)
    )
    (property "Manufacturer" "Bourns" (at 38.1 256.54 0)
      (effects (font (size 1.524 1.524)) (justify left) hide)
    )
    (property "MPN" "CR0402-FX-1002GLF" (at 40.64 256.54 0)
      (effects (font (size 1.524 1.524)) (justify left) hide)
    )
    (property "Val" "10k" (at 50.546 260.35 90)
      (effects (font (size 1.27 1.27)) (justify right))
    )
    (property "License" "Apache-2.0" (at 73.66 241.3 0)
      (effects (font (size 1.27 1.27) (thickness 0.15)) (justify left bottom) hide)
    )
    (property "Author" "Antmicro" (at 76.2 241.3 0)
      (effects (font (size 1.27 1.27) (thickness 0.15)) (justify left bottom) hide)
    )
    (property "Tolerance" "1%" (at 58.42 241.3 0)
      (effects (font (size 1.27 1.27)) (justify left bottom) hide)
    )
    (property "Public" "False" (at 78.74 241.3 0)
      (effects (font (size 1.27 1.27)) (justify left bottom) hide)
    )
    (pin "1")
    (pin "2")
    (instances
      (project "ecp5-dc-scm"
        (path ""
          (reference "R131") (unit 1)
        )
      )
    )
  )

  (symbol (lib_id "antmicroCapacitors0402:C_100n_0402") (at 48.26 273.05 90) (unit 1)
    (in_bom yes) (on_board yes) (dnp no)
    (property "Reference" "C208" (at 45.466 269.2336 90)
      (effects (font (size 1.524 1.524)) (justify left))
    )
    (property "Value" "C_100n_0402" (at 52.07 273.05 0)
      (effects (font (size 1.524 1.524)) hide)
    )
    (property "Footprint" "antmicro-footprints:C_0402_1005Metric" (at 43.18 267.97 0)
      (effects (font (size 1.524 1.524)) (justify left) hide)
    )
    (property "Datasheet" "https://www.murata.com/products/productdetail?partno=GRM155R61H104KE14%23" (at 48.26 273.05 0)
      (effects (font (size 1.27 1.27)) hide)
    )
    (property "Manufacturer" "Murata" (at 38.1 267.97 0)
      (effects (font (size 1.524 1.524)) (justify left) hide)
    )
    (property "MPN" "GRM155R61H104KE14D" (at 40.64 267.97 0)
      (effects (font (size 1.524 1.524)) (justify left) hide)
    )
    (property "Val" "100n" (at 45.466 271.7736 90)
      (effects (font (size 1.27 1.27)) (justify left))
    )
    (property "License" "Apache-2.0" (at 71.12 252.73 0)
      (effects (font (size 1.27 1.27) (thickness 0.15)) (justify left bottom) hide)
    )
    (property "Author" "Antmicro" (at 73.66 252.73 0)
      (effects (font (size 1.27 1.27) (thickness 0.15)) (justify left bottom) hide)
    )
    (property "Voltage" "50V" (at 76.2 252.73 0)
      (effects (font (size 1.27 1.27)) (justify left bottom) hide)
    )
    (property "Dielectric" "X5R" (at 78.74 252.73 0)
      (effects (font (size 1.27 1.27)) (justify left bottom) hide)
    )
    (property "Public" "False" (at 81.28 252.73 0)
      (effects (font (size 1.27 1.27)) (justify left bottom) hide)
    )
    (pin "1")
    (pin "2")
    (instances
      (project "ecp5-dc-scm"
        (path ""
          (reference "C208") (unit 1)
        )
      )
    )
  )

  (symbol (lib_id "antmicropower:GND") (at 52.07 278.13 0) (unit 1)
    (in_bom yes) (on_board yes) (dnp no)
    (property "Reference" "#PWR0108" (at 52.07 284.48 0)
      (effects (font (size 1.27 1.27)) hide)
    )
    (property "Value" "GND" (at 52.197 282.5242 0)
      (effects (font (size 1.27 1.27)))
    )
    (property "Footprint" "" (at 52.07 278.13 0)
      (effects (font (size 1.27 1.27)) hide)
    )
    (property "Datasheet" "" (at 52.07 278.13 0)
      (effects (font (size 1.27 1.27)) hide)
    )
    (property "Author" "Antmicro" (at 60.96 285.75 0)
      (effects (font (size 1.27 1.27) (thickness 0.15)) (justify left bottom) hide)
    )
    (property "License" "Apache-2.0" (at 60.96 288.29 0)
      (effects (font (size 1.27 1.27) (thickness 0.15)) (justify left bottom) hide)
    )
    (pin "1")
    (instances
      (project "ecp5-dc-scm"
        (path ""
          (reference "#PWR0108") (unit 1)
        )
      )
    )
  )

  (symbol (lib_id "antmicroCapacitors0402:C_470n_0402") (at 69.85 30.48 90) (mirror x) (unit 1)
    (in_bom yes) (on_board yes) (dnp no)
    (property "Reference" "C207" (at 73.025 31.75 90)
      (effects (font (size 1.524 1.524)) (justify right))
    )
    (property "Value" "C_470n_0402" (at 73.66 30.48 0)
      (effects (font (size 1.524 1.524)) hide)
    )
    (property "Footprint" "antmicro-footprints:C_0402_1005Metric" (at 64.77 35.56 0)
      (effects (font (size 1.524 1.524)) (justify left) hide)
    )
    (property "Datasheet" "https://product.tdk.com/en/search/capacitor/ceramic/mlcc/info?part_no=C1005X5R1E474M050BB" (at 69.85 30.48 0)
      (effects (font (size 1.27 1.27)) hide)
    )
    (property "Manufacturer" "TDK" (at 59.69 35.56 0)
      (effects (font (size 1.524 1.524)) (justify left) hide)
    )
    (property "MPN" "C1005X5R1E474M050BB" (at 62.23 35.56 0)
      (effects (font (size 1.524 1.524)) (justify left) hide)
    )
    (property "Val" "470n" (at 73.025 34.29 90)
      (effects (font (size 1.27 1.27)) (justify right))
    )
    (property "License" "Apache-2.0" (at 92.71 50.8 0)
      (effects (font (size 1.27 1.27) (thickness 0.15)) (justify left bottom) hide)
    )
    (property "Author" "Antmicro" (at 95.25 50.8 0)
      (effects (font (size 1.27 1.27) (thickness 0.15)) (justify left bottom) hide)
    )
    (property "Voltage" "" (at 97.79 50.8 0)
      (effects (font (size 1.27 1.27)) (justify left bottom) hide)
    )
    (property "Dielectric" "" (at 100.33 50.8 0)
      (effects (font (size 1.27 1.27)) (justify left bottom) hide)
    )
    (property "Public" "False" (at 102.87 50.8 0)
      (effects (font (size 1.27 1.27)) (justify left bottom) hide)
    )
    (pin "1")
    (pin "2")
    (instances
      (project "ecp5-dc-scm"
        (path ""
          (reference "C207") (unit 1)
        )
      )
    )
  )

  (symbol (lib_id "antmicroCapacitors0402:C_470n_0402") (at 59.69 30.48 90) (mirror x) (unit 1)
    (in_bom yes) (on_board yes) (dnp no) (fields_autoplaced)
    (property "Reference" "C206" (at 62.23 31.7563 90)
      (effects (font (size 1.524 1.524)) (justify right))
    )
    (property "Value" "C_470n_0402" (at 63.5 30.48 0)
      (effects (font (size 1.524 1.524)) hide)
    )
    (property "Footprint" "antmicro-footprints:C_0402_1005Metric" (at 54.61 35.56 0)
      (effects (font (size 1.524 1.524)) (justify left) hide)
    )
    (property "Datasheet" "https://product.tdk.com/en/search/capacitor/ceramic/mlcc/info?part_no=C1005X5R1E474M050BB" (at 59.69 30.48 0)
      (effects (font (size 1.27 1.27)) hide)
    )
    (property "Manufacturer" "TDK" (at 49.53 35.56 0)
      (effects (font (size 1.524 1.524)) (justify left) hide)
    )
    (property "MPN" "C1005X5R1E474M050BB" (at 52.07 35.56 0)
      (effects (font (size 1.524 1.524)) (justify left) hide)
    )
    (property "Val" "470n" (at 62.23 34.2963 90)
      (effects (font (size 1.27 1.27)) (justify right))
    )
    (property "License" "Apache-2.0" (at 82.55 50.8 0)
      (effects (font (size 1.27 1.27) (thickness 0.15)) (justify left bottom) hide)
    )
    (property "Author" "Antmicro" (at 85.09 50.8 0)
      (effects (font (size 1.27 1.27) (thickness 0.15)) (justify left bottom) hide)
    )
    (property "Voltage" "" (at 87.63 50.8 0)
      (effects (font (size 1.27 1.27)) (justify left bottom) hide)
    )
    (property "Dielectric" "" (at 90.17 50.8 0)
      (effects (font (size 1.27 1.27)) (justify left bottom) hide)
    )
    (property "Public" "False" (at 92.71 50.8 0)
      (effects (font (size 1.27 1.27)) (justify left bottom) hide)
    )
    (pin "1")
    (pin "2")
    (instances
      (project "ecp5-dc-scm"
        (path ""
          (reference "C206") (unit 1)
        )
      )
    )
  )

  (symbol (lib_id "antmicroCapacitors0402:C_470n_0402") (at 48.26 30.48 90) (mirror x) (unit 1)
    (in_bom yes) (on_board yes) (dnp no) (fields_autoplaced)
    (property "Reference" "C205" (at 51.435 31.7563 90)
      (effects (font (size 1.524 1.524)) (justify right))
    )
    (property "Value" "C_470n_0402" (at 52.07 30.48 0)
      (effects (font (size 1.524 1.524)) hide)
    )
    (property "Footprint" "antmicro-footprints:C_0402_1005Metric" (at 43.18 35.56 0)
      (effects (font (size 1.524 1.524)) (justify left) hide)
    )
    (property "Datasheet" "https://product.tdk.com/en/search/capacitor/ceramic/mlcc/info?part_no=C1005X5R1E474M050BB" (at 48.26 30.48 0)
      (effects (font (size 1.27 1.27)) hide)
    )
    (property "Manufacturer" "TDK" (at 38.1 35.56 0)
      (effects (font (size 1.524 1.524)) (justify left) hide)
    )
    (property "MPN" "C1005X5R1E474M050BB" (at 40.64 35.56 0)
      (effects (font (size 1.524 1.524)) (justify left) hide)
    )
    (property "Val" "470n" (at 51.435 34.2963 90)
      (effects (font (size 1.27 1.27)) (justify right))
    )
    (property "License" "Apache-2.0" (at 71.12 50.8 0)
      (effects (font (size 1.27 1.27) (thickness 0.15)) (justify left bottom) hide)
    )
    (property "Author" "Antmicro" (at 73.66 50.8 0)
      (effects (font (size 1.27 1.27) (thickness 0.15)) (justify left bottom) hide)
    )
    (property "Voltage" "" (at 76.2 50.8 0)
      (effects (font (size 1.27 1.27)) (justify left bottom) hide)
    )
    (property "Dielectric" "" (at 78.74 50.8 0)
      (effects (font (size 1.27 1.27)) (justify left bottom) hide)
    )
    (property "Public" "False" (at 81.28 50.8 0)
      (effects (font (size 1.27 1.27)) (justify left bottom) hide)
    )
    (pin "1")
    (pin "2")
    (instances
      (project "ecp5-dc-scm"
        (path ""
          (reference "C205") (unit 1)
        )
      )
    )
  )

  (symbol (lib_id "antmicroCapacitors0402:C_470n_0402") (at 38.1 30.48 270) (unit 1)
    (in_bom yes) (on_board yes) (dnp no)
    (property "Reference" "C204" (at 41.275 31.7563 90)
      (effects (font (size 1.524 1.524)) (justify left))
    )
    (property "Value" "C_470n_0402" (at 34.29 30.48 0)
      (effects (font (size 1.524 1.524)) hide)
    )
    (property "Footprint" "antmicro-footprints:C_0402_1005Metric" (at 43.18 35.56 0)
      (effects (font (size 1.524 1.524)) (justify left) hide)
    )
    (property "Datasheet" "https://product.tdk.com/en/search/capacitor/ceramic/mlcc/info?part_no=C1005X5R1E474M050BB" (at 38.1 30.48 0)
      (effects (font (size 1.27 1.27)) hide)
    )
    (property "Manufacturer" "TDK" (at 48.26 35.56 0)
      (effects (font (size 1.524 1.524)) (justify left) hide)
    )
    (property "MPN" "C1005X5R1E474M050BB" (at 45.72 35.56 0)
      (effects (font (size 1.524 1.524)) (justify left) hide)
    )
    (property "Val" "470n" (at 41.275 34.2963 90)
      (effects (font (size 1.27 1.27)) (justify left))
    )
    (property "License" "Apache-2.0" (at 15.24 50.8 0)
      (effects (font (size 1.27 1.27) (thickness 0.15)) (justify left bottom) hide)
    )
    (property "Author" "Antmicro" (at 12.7 50.8 0)
      (effects (font (size 1.27 1.27) (thickness 0.15)) (justify left bottom) hide)
    )
    (property "Voltage" "" (at 10.16 50.8 0)
      (effects (font (size 1.27 1.27)) (justify left bottom) hide)
    )
    (property "Dielectric" "" (at 7.62 50.8 0)
      (effects (font (size 1.27 1.27)) (justify left bottom) hide)
    )
    (property "Public" "False" (at 5.08 50.8 0)
      (effects (font (size 1.27 1.27)) (justify left bottom) hide)
    )
    (pin "1")
    (pin "2")
    (instances
      (project "ecp5-dc-scm"
        (path ""
          (reference "C204") (unit 1)
        )
      )
    )
  )

  (symbol (lib_id "antmicroCapacitors0402:C_4u7_0402") (at 26.67 30.48 270) (unit 1)
    (in_bom yes) (on_board yes) (dnp no)
    (property "Reference" "C203" (at 29.21 31.7563 90)
      (effects (font (size 1.524 1.524)) (justify left))
    )
    (property "Value" "C_4u7_0402" (at 22.86 30.48 0)
      (effects (font (size 1.524 1.524)) hide)
    )
    (property "Footprint" "antmicro-footprints:C_0402_1005Metric" (at 31.75 35.56 0)
      (effects (font (size 1.524 1.524)) (justify left) hide)
    )
    (property "Datasheet" "https://www.murata.com/products/productdetail?partno=GRM155R61A475MEAA%23" (at 26.67 30.48 0)
      (effects (font (size 1.27 1.27)) hide)
    )
    (property "Manufacturer" "Murata" (at 36.83 35.56 0)
      (effects (font (size 1.524 1.524)) (justify left) hide)
    )
    (property "MPN" "GRM155R61A475MEAAD" (at 34.29 35.56 0)
      (effects (font (size 1.524 1.524)) (justify left) hide)
    )
    (property "Val" "4u7" (at 29.21 34.2963 90)
      (effects (font (size 1.27 1.27)) (justify left))
    )
    (property "License" "Apache-2.0" (at 3.81 50.8 0)
      (effects (font (size 1.27 1.27) (thickness 0.15)) (justify left bottom) hide)
    )
    (property "Author" "Antmicro" (at 1.27 50.8 0)
      (effects (font (size 1.27 1.27) (thickness 0.15)) (justify left bottom) hide)
    )
    (property "Voltage" "" (at -1.27 50.8 0)
      (effects (font (size 1.27 1.27)) (justify left bottom) hide)
    )
    (property "Dielectric" "" (at -3.81 50.8 0)
      (effects (font (size 1.27 1.27)) (justify left bottom) hide)
    )
    (property "Public" "False" (at -6.35 50.8 0)
      (effects (font (size 1.27 1.27)) (justify left bottom) hide)
    )
    (pin "1")
    (pin "2")
    (instances
      (project "ecp5-dc-scm"
        (path ""
          (reference "C203") (unit 1)
        )
      )
    )
  )

  (symbol (lib_id "antmicroCapacitors0402:C_470n_0402") (at 135.89 30.48 90) (mirror x) (unit 1)
    (in_bom yes) (on_board yes) (dnp no) (fields_autoplaced)
    (property "Reference" "C215" (at 138.43 31.7563 90)
      (effects (font (size 1.524 1.524)) (justify right))
    )
    (property "Value" "C_470n_0402" (at 139.7 30.48 0)
      (effects (font (size 1.524 1.524)) hide)
    )
    (property "Footprint" "antmicro-footprints:C_0402_1005Metric" (at 130.81 35.56 0)
      (effects (font (size 1.524 1.524)) (justify left) hide)
    )
    (property "Datasheet" "https://product.tdk.com/en/search/capacitor/ceramic/mlcc/info?part_no=C1005X5R1E474M050BB" (at 135.89 30.48 0)
      (effects (font (size 1.27 1.27)) hide)
    )
    (property "Manufacturer" "TDK" (at 125.73 35.56 0)
      (effects (font (size 1.524 1.524)) (justify left) hide)
    )
    (property "MPN" "C1005X5R1E474M050BB" (at 128.27 35.56 0)
      (effects (font (size 1.524 1.524)) (justify left) hide)
    )
    (property "Val" "470n" (at 138.43 34.2963 90)
      (effects (font (size 1.27 1.27)) (justify right))
    )
    (property "License" "Apache-2.0" (at 158.75 50.8 0)
      (effects (font (size 1.27 1.27) (thickness 0.15)) (justify left bottom) hide)
    )
    (property "Author" "Antmicro" (at 161.29 50.8 0)
      (effects (font (size 1.27 1.27) (thickness 0.15)) (justify left bottom) hide)
    )
    (property "Voltage" "" (at 163.83 50.8 0)
      (effects (font (size 1.27 1.27)) (justify left bottom) hide)
    )
    (property "Dielectric" "" (at 166.37 50.8 0)
      (effects (font (size 1.27 1.27)) (justify left bottom) hide)
    )
    (property "Public" "False" (at 168.91 50.8 0)
      (effects (font (size 1.27 1.27)) (justify left bottom) hide)
    )
    (pin "1")
    (pin "2")
    (instances
      (project "ecp5-dc-scm"
        (path ""
          (reference "C215") (unit 1)
        )
      )
    )
  )

  (symbol (lib_id "antmicroCapacitors0402:C_470n_0402") (at 125.73 30.48 90) (mirror x) (unit 1)
    (in_bom yes) (on_board yes) (dnp no) (fields_autoplaced)
    (property "Reference" "C214" (at 128.27 31.7563 90)
      (effects (font (size 1.524 1.524)) (justify right))
    )
    (property "Value" "C_470n_0402" (at 129.54 30.48 0)
      (effects (font (size 1.524 1.524)) hide)
    )
    (property "Footprint" "antmicro-footprints:C_0402_1005Metric" (at 120.65 35.56 0)
      (effects (font (size 1.524 1.524)) (justify left) hide)
    )
    (property "Datasheet" "https://product.tdk.com/en/search/capacitor/ceramic/mlcc/info?part_no=C1005X5R1E474M050BB" (at 125.73 30.48 0)
      (effects (font (size 1.27 1.27)) hide)
    )
    (property "Manufacturer" "TDK" (at 115.57 35.56 0)
      (effects (font (size 1.524 1.524)) (justify left) hide)
    )
    (property "MPN" "C1005X5R1E474M050BB" (at 118.11 35.56 0)
      (effects (font (size 1.524 1.524)) (justify left) hide)
    )
    (property "Val" "470n" (at 128.27 34.2963 90)
      (effects (font (size 1.27 1.27)) (justify right))
    )
    (property "License" "Apache-2.0" (at 148.59 50.8 0)
      (effects (font (size 1.27 1.27) (thickness 0.15)) (justify left bottom) hide)
    )
    (property "Author" "Antmicro" (at 151.13 50.8 0)
      (effects (font (size 1.27 1.27) (thickness 0.15)) (justify left bottom) hide)
    )
    (property "Voltage" "" (at 153.67 50.8 0)
      (effects (font (size 1.27 1.27)) (justify left bottom) hide)
    )
    (property "Dielectric" "" (at 156.21 50.8 0)
      (effects (font (size 1.27 1.27)) (justify left bottom) hide)
    )
    (property "Public" "False" (at 158.75 50.8 0)
      (effects (font (size 1.27 1.27)) (justify left bottom) hide)
    )
    (pin "1")
    (pin "2")
    (instances
      (project "ecp5-dc-scm"
        (path ""
          (reference "C214") (unit 1)
        )
      )
    )
  )

  (symbol (lib_id "antmicroCapacitors0402:C_470n_0402") (at 187.96 30.48 270) (unit 1)
    (in_bom yes) (on_board yes) (dnp no)
    (property "Reference" "C223" (at 190.5 31.7563 90)
      (effects (font (size 1.524 1.524)) (justify left))
    )
    (property "Value" "C_470n_0402" (at 184.15 30.48 0)
      (effects (font (size 1.524 1.524)) hide)
    )
    (property "Footprint" "antmicro-footprints:C_0402_1005Metric" (at 193.04 35.56 0)
      (effects (font (size 1.524 1.524)) (justify left) hide)
    )
    (property "Datasheet" "https://product.tdk.com/en/search/capacitor/ceramic/mlcc/info?part_no=C1005X5R1E474M050BB" (at 187.96 30.48 0)
      (effects (font (size 1.27 1.27)) hide)
    )
    (property "Manufacturer" "TDK" (at 198.12 35.56 0)
      (effects (font (size 1.524 1.524)) (justify left) hide)
    )
    (property "MPN" "C1005X5R1E474M050BB" (at 195.58 35.56 0)
      (effects (font (size 1.524 1.524)) (justify left) hide)
    )
    (property "Val" "470n" (at 190.5 34.2963 90)
      (effects (font (size 1.27 1.27)) (justify left))
    )
    (property "License" "Apache-2.0" (at 165.1 50.8 0)
      (effects (font (size 1.27 1.27) (thickness 0.15)) (justify left bottom) hide)
    )
    (property "Author" "Antmicro" (at 162.56 50.8 0)
      (effects (font (size 1.27 1.27) (thickness 0.15)) (justify left bottom) hide)
    )
    (property "Voltage" "" (at 160.02 50.8 0)
      (effects (font (size 1.27 1.27)) (justify left bottom) hide)
    )
    (property "Dielectric" "" (at 157.48 50.8 0)
      (effects (font (size 1.27 1.27)) (justify left bottom) hide)
    )
    (property "Public" "False" (at 154.94 50.8 0)
      (effects (font (size 1.27 1.27)) (justify left bottom) hide)
    )
    (pin "1")
    (pin "2")
    (instances
      (project "ecp5-dc-scm"
        (path ""
          (reference "C223") (unit 1)
        )
      )
    )
  )

  (symbol (lib_id "antmicroCapacitors0402:C_470n_0402") (at 238.76 30.48 90) (mirror x) (unit 1)
    (in_bom yes) (on_board yes) (dnp no) (fields_autoplaced)
    (property "Reference" "C226" (at 241.935 31.7563 90)
      (effects (font (size 1.524 1.524)) (justify right))
    )
    (property "Value" "C_470n_0402" (at 242.57 30.48 0)
      (effects (font (size 1.524 1.524)) hide)
    )
    (property "Footprint" "antmicro-footprints:C_0402_1005Metric" (at 233.68 35.56 0)
      (effects (font (size 1.524 1.524)) (justify left) hide)
    )
    (property "Datasheet" "https://product.tdk.com/en/search/capacitor/ceramic/mlcc/info?part_no=C1005X5R1E474M050BB" (at 238.76 30.48 0)
      (effects (font (size 1.27 1.27)) hide)
    )
    (property "Manufacturer" "TDK" (at 228.6 35.56 0)
      (effects (font (size 1.524 1.524)) (justify left) hide)
    )
    (property "MPN" "C1005X5R1E474M050BB" (at 231.14 35.56 0)
      (effects (font (size 1.524 1.524)) (justify left) hide)
    )
    (property "Val" "470n" (at 241.935 34.2963 90)
      (effects (font (size 1.27 1.27)) (justify right))
    )
    (property "License" "Apache-2.0" (at 261.62 50.8 0)
      (effects (font (size 1.27 1.27) (thickness 0.15)) (justify left bottom) hide)
    )
    (property "Author" "Antmicro" (at 264.16 50.8 0)
      (effects (font (size 1.27 1.27) (thickness 0.15)) (justify left bottom) hide)
    )
    (property "Voltage" "" (at 266.7 50.8 0)
      (effects (font (size 1.27 1.27)) (justify left bottom) hide)
    )
    (property "Dielectric" "" (at 269.24 50.8 0)
      (effects (font (size 1.27 1.27)) (justify left bottom) hide)
    )
    (property "Public" "False" (at 271.78 50.8 0)
      (effects (font (size 1.27 1.27)) (justify left bottom) hide)
    )
    (pin "1")
    (pin "2")
    (instances
      (project "ecp5-dc-scm"
        (path ""
          (reference "C226") (unit 1)
        )
      )
    )
  )

  (symbol (lib_id "antmicroCapacitors0402:C_4u7_0402") (at 227.33 30.48 270) (unit 1)
    (in_bom yes) (on_board yes) (dnp no)
    (property "Reference" "C225" (at 230.505 31.7563 90)
      (effects (font (size 1.524 1.524)) (justify left))
    )
    (property "Value" "C_4u7_0402" (at 223.52 30.48 0)
      (effects (font (size 1.524 1.524)) hide)
    )
    (property "Footprint" "antmicro-footprints:C_0402_1005Metric" (at 232.41 35.56 0)
      (effects (font (size 1.524 1.524)) (justify left) hide)
    )
    (property "Datasheet" "https://www.murata.com/products/productdetail?partno=GRM155R61A475MEAA%23" (at 227.33 30.48 0)
      (effects (font (size 1.27 1.27)) hide)
    )
    (property "Manufacturer" "Murata" (at 237.49 35.56 0)
      (effects (font (size 1.524 1.524)) (justify left) hide)
    )
    (property "MPN" "GRM155R61A475MEAAD" (at 234.95 35.56 0)
      (effects (font (size 1.524 1.524)) (justify left) hide)
    )
    (property "Val" "4u7" (at 230.505 34.2963 90)
      (effects (font (size 1.27 1.27)) (justify left))
    )
    (property "License" "Apache-2.0" (at 204.47 50.8 0)
      (effects (font (size 1.27 1.27) (thickness 0.15)) (justify left bottom) hide)
    )
    (property "Author" "Antmicro" (at 201.93 50.8 0)
      (effects (font (size 1.27 1.27) (thickness 0.15)) (justify left bottom) hide)
    )
    (property "Voltage" "" (at 199.39 50.8 0)
      (effects (font (size 1.27 1.27)) (justify left bottom) hide)
    )
    (property "Dielectric" "" (at 196.85 50.8 0)
      (effects (font (size 1.27 1.27)) (justify left bottom) hide)
    )
    (property "Public" "False" (at 194.31 50.8 0)
      (effects (font (size 1.27 1.27)) (justify left bottom) hide)
    )
    (pin "1")
    (pin "2")
    (instances
      (project "ecp5-dc-scm"
        (path ""
          (reference "C225") (unit 1)
        )
      )
    )
  )

  (symbol (lib_id "antmicroCapacitors0402:C_470n_0402") (at 309.88 30.48 90) (mirror x) (unit 1)
    (in_bom yes) (on_board yes) (dnp no) (fields_autoplaced)
    (property "Reference" "C232" (at 313.055 31.7563 90)
      (effects (font (size 1.524 1.524)) (justify right))
    )
    (property "Value" "C_470n_0402" (at 313.69 30.48 0)
      (effects (font (size 1.524 1.524)) hide)
    )
    (property "Footprint" "antmicro-footprints:C_0402_1005Metric" (at 304.8 35.56 0)
      (effects (font (size 1.524 1.524)) (justify left) hide)
    )
    (property "Datasheet" "https://product.tdk.com/en/search/capacitor/ceramic/mlcc/info?part_no=C1005X5R1E474M050BB" (at 309.88 30.48 0)
      (effects (font (size 1.27 1.27)) hide)
    )
    (property "Manufacturer" "TDK" (at 299.72 35.56 0)
      (effects (font (size 1.524 1.524)) (justify left) hide)
    )
    (property "MPN" "C1005X5R1E474M050BB" (at 302.26 35.56 0)
      (effects (font (size 1.524 1.524)) (justify left) hide)
    )
    (property "Val" "470n" (at 313.055 34.2963 90)
      (effects (font (size 1.27 1.27)) (justify right))
    )
    (property "License" "Apache-2.0" (at 332.74 50.8 0)
      (effects (font (size 1.27 1.27) (thickness 0.15)) (justify left bottom) hide)
    )
    (property "Author" "Antmicro" (at 335.28 50.8 0)
      (effects (font (size 1.27 1.27) (thickness 0.15)) (justify left bottom) hide)
    )
    (property "Voltage" "" (at 337.82 50.8 0)
      (effects (font (size 1.27 1.27)) (justify left bottom) hide)
    )
    (property "Dielectric" "" (at 340.36 50.8 0)
      (effects (font (size 1.27 1.27)) (justify left bottom) hide)
    )
    (property "Public" "False" (at 342.9 50.8 0)
      (effects (font (size 1.27 1.27)) (justify left bottom) hide)
    )
    (pin "1")
    (pin "2")
    (instances
      (project "ecp5-dc-scm"
        (path ""
          (reference "C232") (unit 1)
        )
      )
    )
  )

  (symbol (lib_id "antmicroCapacitors0402:C_470n_0402") (at 299.72 35.56 90) (unit 1)
    (in_bom yes) (on_board yes) (dnp no) (fields_autoplaced)
    (property "Reference" "C231" (at 302.895 31.7436 90)
      (effects (font (size 1.524 1.524)) (justify right))
    )
    (property "Value" "C_470n_0402" (at 303.53 35.56 0)
      (effects (font (size 1.524 1.524)) hide)
    )
    (property "Footprint" "antmicro-footprints:C_0402_1005Metric" (at 294.64 30.48 0)
      (effects (font (size 1.524 1.524)) (justify left) hide)
    )
    (property "Datasheet" "https://product.tdk.com/en/search/capacitor/ceramic/mlcc/info?part_no=C1005X5R1E474M050BB" (at 299.72 35.56 0)
      (effects (font (size 1.27 1.27)) hide)
    )
    (property "Manufacturer" "TDK" (at 289.56 30.48 0)
      (effects (font (size 1.524 1.524)) (justify left) hide)
    )
    (property "MPN" "C1005X5R1E474M050BB" (at 292.1 30.48 0)
      (effects (font (size 1.524 1.524)) (justify left) hide)
    )
    (property "Val" "470n" (at 302.895 34.2836 90)
      (effects (font (size 1.27 1.27)) (justify right))
    )
    (property "License" "Apache-2.0" (at 322.58 15.24 0)
      (effects (font (size 1.27 1.27) (thickness 0.15)) (justify left bottom) hide)
    )
    (property "Author" "Antmicro" (at 325.12 15.24 0)
      (effects (font (size 1.27 1.27) (thickness 0.15)) (justify left bottom) hide)
    )
    (property "Voltage" "" (at 327.66 15.24 0)
      (effects (font (size 1.27 1.27)) (justify left bottom) hide)
    )
    (property "Dielectric" "" (at 330.2 15.24 0)
      (effects (font (size 1.27 1.27)) (justify left bottom) hide)
    )
    (property "Public" "False" (at 332.74 15.24 0)
      (effects (font (size 1.27 1.27)) (justify left bottom) hide)
    )
    (pin "1")
    (pin "2")
    (instances
      (project "ecp5-dc-scm"
        (path ""
          (reference "C231") (unit 1)
        )
      )
    )
  )

  (symbol (lib_id "antmicroCapacitors0402:C_4u7_0402") (at 353.06 29.21 90) (mirror x) (unit 1)
    (in_bom yes) (on_board yes) (dnp no)
    (property "Reference" "C235" (at 354.584 30.48 90)
      (effects (font (size 1.524 1.524)) (justify right))
    )
    (property "Value" "C_4u7_0402" (at 356.87 29.21 0)
      (effects (font (size 1.524 1.524)) hide)
    )
    (property "Footprint" "antmicro-footprints:C_0402_1005Metric" (at 347.98 34.29 0)
      (effects (font (size 1.524 1.524)) (justify left) hide)
    )
    (property "Datasheet" "https://www.murata.com/products/productdetail?partno=GRM155R61A475MEAA%23" (at 353.06 29.21 0)
      (effects (font (size 1.27 1.27)) hide)
    )
    (property "Manufacturer" "Murata" (at 342.9 34.29 0)
      (effects (font (size 1.524 1.524)) (justify left) hide)
    )
    (property "MPN" "GRM155R61A475MEAAD" (at 345.44 34.29 0)
      (effects (font (size 1.524 1.524)) (justify left) hide)
    )
    (property "Val" "4u7" (at 354.838 33.02 90)
      (effects (font (size 1.27 1.27)) (justify right))
    )
    (property "License" "Apache-2.0" (at 375.92 49.53 0)
      (effects (font (size 1.27 1.27) (thickness 0.15)) (justify left bottom) hide)
    )
    (property "Author" "Antmicro" (at 378.46 49.53 0)
      (effects (font (size 1.27 1.27) (thickness 0.15)) (justify left bottom) hide)
    )
    (property "Voltage" "" (at 381 49.53 0)
      (effects (font (size 1.27 1.27)) (justify left bottom) hide)
    )
    (property "Dielectric" "" (at 383.54 49.53 0)
      (effects (font (size 1.27 1.27)) (justify left bottom) hide)
    )
    (property "Public" "False" (at 386.08 49.53 0)
      (effects (font (size 1.27 1.27)) (justify left bottom) hide)
    )
    (pin "1")
    (pin "2")
    (instances
      (project "ecp5-dc-scm"
        (path ""
          (reference "C235") (unit 1)
        )
      )
    )
  )

  (symbol (lib_id "antmicroCapacitors0402:C_470n_0402") (at 97.79 187.96 90) (mirror x) (unit 1)
    (in_bom yes) (on_board yes) (dnp no) (fields_autoplaced)
    (property "Reference" "C210" (at 101.092 189.2363 90)
      (effects (font (size 1.524 1.524)) (justify right))
    )
    (property "Value" "C_470n_0402" (at 101.6 187.96 0)
      (effects (font (size 1.524 1.524)) hide)
    )
    (property "Footprint" "antmicro-footprints:C_0402_1005Metric" (at 92.71 193.04 0)
      (effects (font (size 1.524 1.524)) (justify left) hide)
    )
    (property "Datasheet" "https://product.tdk.com/en/search/capacitor/ceramic/mlcc/info?part_no=C1005X5R1E474M050BB" (at 97.79 187.96 0)
      (effects (font (size 1.27 1.27)) hide)
    )
    (property "Manufacturer" "TDK" (at 87.63 193.04 0)
      (effects (font (size 1.524 1.524)) (justify left) hide)
    )
    (property "MPN" "C1005X5R1E474M050BB" (at 90.17 193.04 0)
      (effects (font (size 1.524 1.524)) (justify left) hide)
    )
    (property "Val" "470n" (at 101.092 191.7763 90)
      (effects (font (size 1.27 1.27)) (justify right))
    )
    (property "License" "Apache-2.0" (at 120.65 208.28 0)
      (effects (font (size 1.27 1.27) (thickness 0.15)) (justify left bottom) hide)
    )
    (property "Author" "Antmicro" (at 123.19 208.28 0)
      (effects (font (size 1.27 1.27) (thickness 0.15)) (justify left bottom) hide)
    )
    (property "Voltage" "" (at 125.73 208.28 0)
      (effects (font (size 1.27 1.27)) (justify left bottom) hide)
    )
    (property "Dielectric" "" (at 128.27 208.28 0)
      (effects (font (size 1.27 1.27)) (justify left bottom) hide)
    )
    (property "Public" "False" (at 130.81 208.28 0)
      (effects (font (size 1.27 1.27)) (justify left bottom) hide)
    )
    (pin "1")
    (pin "2")
    (instances
      (project "ecp5-dc-scm"
        (path ""
          (reference "C210") (unit 1)
        )
      )
    )
  )

  (symbol (lib_id "antmicropower:GND") (at 157.48 200.66 0) (unit 1)
    (in_bom yes) (on_board yes) (dnp no)
    (property "Reference" "#PWR0113" (at 157.48 207.01 0)
      (effects (font (size 1.27 1.27)) hide)
    )
    (property "Value" "GND" (at 157.607 205.0542 0)
      (effects (font (size 1.27 1.27)))
    )
    (property "Footprint" "" (at 157.48 200.66 0)
      (effects (font (size 1.27 1.27)) hide)
    )
    (property "Datasheet" "" (at 157.48 200.66 0)
      (effects (font (size 1.27 1.27)) hide)
    )
    (property "Author" "Antmicro" (at 166.37 208.28 0)
      (effects (font (size 1.27 1.27) (thickness 0.15)) (justify left bottom) hide)
    )
    (property "License" "Apache-2.0" (at 166.37 210.82 0)
      (effects (font (size 1.27 1.27) (thickness 0.15)) (justify left bottom) hide)
    )
    (pin "1")
    (instances
      (project "ecp5-dc-scm"
        (path ""
          (reference "#PWR0113") (unit 1)
        )
      )
    )
  )

  (symbol (lib_id "antmicropower:GND") (at 93.98 40.64 0) (unit 1)
    (in_bom yes) (on_board yes) (dnp no)
    (property "Reference" "#PWR0111" (at 93.98 46.99 0)
      (effects (font (size 1.27 1.27)) hide)
    )
    (property "Value" "GND" (at 94.107 45.0342 0)
      (effects (font (size 1.27 1.27)))
    )
    (property "Footprint" "" (at 93.98 40.64 0)
      (effects (font (size 1.27 1.27)) hide)
    )
    (property "Datasheet" "" (at 93.98 40.64 0)
      (effects (font (size 1.27 1.27)) hide)
    )
    (property "Author" "Antmicro" (at 102.87 48.26 0)
      (effects (font (size 1.27 1.27) (thickness 0.15)) (justify left bottom) hide)
    )
    (property "License" "Apache-2.0" (at 102.87 50.8 0)
      (effects (font (size 1.27 1.27) (thickness 0.15)) (justify left bottom) hide)
    )
    (pin "1")
    (instances
      (project "ecp5-dc-scm"
        (path ""
          (reference "#PWR0111") (unit 1)
        )
      )
    )
  )

  (symbol (lib_id "antmicropower:GND") (at 157.48 40.64 0) (unit 1)
    (in_bom yes) (on_board yes) (dnp no)
    (property "Reference" "#PWR0114" (at 157.48 46.99 0)
      (effects (font (size 1.27 1.27)) hide)
    )
    (property "Value" "GND" (at 157.607 45.0342 0)
      (effects (font (size 1.27 1.27)))
    )
    (property "Footprint" "" (at 157.48 40.64 0)
      (effects (font (size 1.27 1.27)) hide)
    )
    (property "Datasheet" "" (at 157.48 40.64 0)
      (effects (font (size 1.27 1.27)) hide)
    )
    (property "Author" "Antmicro" (at 166.37 48.26 0)
      (effects (font (size 1.27 1.27) (thickness 0.15)) (justify left bottom) hide)
    )
    (property "License" "Apache-2.0" (at 166.37 50.8 0)
      (effects (font (size 1.27 1.27) (thickness 0.15)) (justify left bottom) hide)
    )
    (pin "1")
    (instances
      (project "ecp5-dc-scm"
        (path ""
          (reference "#PWR0114") (unit 1)
        )
      )
    )
  )

  (symbol (lib_id "antmicropower:GND") (at 227.33 40.64 0) (unit 1)
    (in_bom yes) (on_board yes) (dnp no)
    (property "Reference" "#PWR0119" (at 227.33 46.99 0)
      (effects (font (size 1.27 1.27)) hide)
    )
    (property "Value" "GND" (at 227.457 45.0342 0)
      (effects (font (size 1.27 1.27)))
    )
    (property "Footprint" "" (at 227.33 40.64 0)
      (effects (font (size 1.27 1.27)) hide)
    )
    (property "Datasheet" "" (at 227.33 40.64 0)
      (effects (font (size 1.27 1.27)) hide)
    )
    (property "Author" "Antmicro" (at 236.22 48.26 0)
      (effects (font (size 1.27 1.27) (thickness 0.15)) (justify left bottom) hide)
    )
    (property "License" "Apache-2.0" (at 236.22 50.8 0)
      (effects (font (size 1.27 1.27) (thickness 0.15)) (justify left bottom) hide)
    )
    (pin "1")
    (instances
      (project "ecp5-dc-scm"
        (path ""
          (reference "#PWR0119") (unit 1)
        )
      )
    )
  )

  (symbol (lib_id "antmicropower:GND") (at 288.29 39.37 0) (unit 1)
    (in_bom yes) (on_board yes) (dnp no)
    (property "Reference" "#PWR0122" (at 288.29 45.72 0)
      (effects (font (size 1.27 1.27)) hide)
    )
    (property "Value" "GND" (at 288.417 43.7642 0)
      (effects (font (size 1.27 1.27)))
    )
    (property "Footprint" "" (at 288.29 39.37 0)
      (effects (font (size 1.27 1.27)) hide)
    )
    (property "Datasheet" "" (at 288.29 39.37 0)
      (effects (font (size 1.27 1.27)) hide)
    )
    (property "Author" "Antmicro" (at 297.18 46.99 0)
      (effects (font (size 1.27 1.27) (thickness 0.15)) (justify left bottom) hide)
    )
    (property "License" "Apache-2.0" (at 297.18 49.53 0)
      (effects (font (size 1.27 1.27) (thickness 0.15)) (justify left bottom) hide)
    )
    (pin "1")
    (instances
      (project "ecp5-dc-scm"
        (path ""
          (reference "#PWR0122") (unit 1)
        )
      )
    )
  )

  (symbol (lib_id "antmicropower:GND") (at 353.06 39.37 0) (unit 1)
    (in_bom yes) (on_board yes) (dnp no)
    (property "Reference" "#PWR0123" (at 353.06 45.72 0)
      (effects (font (size 1.27 1.27)) hide)
    )
    (property "Value" "GND" (at 353.187 43.7642 0)
      (effects (font (size 1.27 1.27)))
    )
    (property "Footprint" "" (at 353.06 39.37 0)
      (effects (font (size 1.27 1.27)) hide)
    )
    (property "Datasheet" "" (at 353.06 39.37 0)
      (effects (font (size 1.27 1.27)) hide)
    )
    (property "Author" "Antmicro" (at 361.95 46.99 0)
      (effects (font (size 1.27 1.27) (thickness 0.15)) (justify left bottom) hide)
    )
    (property "License" "Apache-2.0" (at 361.95 49.53 0)
      (effects (font (size 1.27 1.27) (thickness 0.15)) (justify left bottom) hide)
    )
    (pin "1")
    (instances
      (project "ecp5-dc-scm"
        (path ""
          (reference "#PWR0123") (unit 1)
        )
      )
    )
  )

  (symbol (lib_id "antmicroResistors0402:R_0R_0402") (at 142.24 218.44 0) (unit 1)
    (in_bom no) (on_board yes) (dnp yes)
    (property "Reference" "R132" (at 139.065 217.424 0)
      (effects (font (size 1.524 1.524)))
    )
    (property "Value" "R_0R_0402" (at 142.24 222.25 0)
      (effects (font (size 1.524 1.524)) hide)
    )
    (property "Footprint" "antmicro-footprints:R_0402_1005Metric" (at 147.32 213.36 0)
      (effects (font (size 1.524 1.524)) (justify left) hide)
    )
    (property "Datasheet" "https://industrial.panasonic.com/cdbs/www-data/pdf/RDA0000/AOA0000C301.pdf" (at 142.24 218.44 0)
      (effects (font (size 1.27 1.27)) hide)
    )
    (property "Manufacturer" "Panasonic" (at 147.32 208.28 0)
      (effects (font (size 1.524 1.524)) (justify left) hide)
    )
    (property "MPN" "ERJ2GE0R00X" (at 147.32 210.82 0)
      (effects (font (size 1.524 1.524)) (justify left) hide)
    )
    (property "Val" "0R" (at 149.098 217.678 0)
      (effects (font (size 1.27 1.27)))
    )
    (property "License" "Apache-2.0" (at 162.56 243.84 0)
      (effects (font (size 1.27 1.27) (thickness 0.15)) (justify left bottom) hide)
    )
    (property "Author" "Antmicro" (at 162.56 246.38 0)
      (effects (font (size 1.27 1.27) (thickness 0.15)) (justify left bottom) hide)
    )
    (property "Tolerance" "~" (at 162.56 228.6 0)
      (effects (font (size 1.27 1.27)) (justify left bottom) hide)
    )
    (property "Current" "1A" (at 162.56 248.92 0)
      (effects (font (size 1.27 1.27) (thickness 0.15)) (justify left bottom) hide)
    )
    (property "Public" "False" (at 162.56 248.92 0)
      (effects (font (size 1.27 1.27)) (justify left bottom) hide)
    )
    (property "DNP" "DNP" (at 0 0 0)
      (effects (font (size 1 1)))
    )
    (pin "1")
    (pin "2")
    (instances
      (project "ecp5-dc-scm"
        (path ""
          (reference "R132") (unit 1)
        )
      )
    )
  )

  (symbol (lib_id "antmicroResistors0402:R_0R_0402") (at 142.24 223.52 0) (unit 1)
    (in_bom no) (on_board yes) (dnp yes)
    (property "Reference" "R133" (at 139.192 225.044 0)
      (effects (font (size 1.524 1.524)))
    )
    (property "Value" "R_0R_0402" (at 142.24 227.33 0)
      (effects (font (size 1.524 1.524)) hide)
    )
    (property "Footprint" "antmicro-footprints:R_0402_1005Metric" (at 147.32 218.44 0)
      (effects (font (size 1.524 1.524)) (justify left) hide)
    )
    (property "Datasheet" "https://industrial.panasonic.com/cdbs/www-data/pdf/RDA0000/AOA0000C301.pdf" (at 142.24 223.52 0)
      (effects (font (size 1.27 1.27)) hide)
    )
    (property "Manufacturer" "Panasonic" (at 147.32 213.36 0)
      (effects (font (size 1.524 1.524)) (justify left) hide)
    )
    (property "MPN" "ERJ2GE0R00X" (at 147.32 215.9 0)
      (effects (font (size 1.524 1.524)) (justify left) hide)
    )
    (property "Val" "0R" (at 149.479 225.171 0)
      (effects (font (size 1.27 1.27)))
    )
    (property "License" "Apache-2.0" (at 162.56 248.92 0)
      (effects (font (size 1.27 1.27) (thickness 0.15)) (justify left bottom) hide)
    )
    (property "Author" "Antmicro" (at 162.56 251.46 0)
      (effects (font (size 1.27 1.27) (thickness 0.15)) (justify left bottom) hide)
    )
    (property "Tolerance" "~" (at 162.56 233.68 0)
      (effects (font (size 1.27 1.27)) (justify left bottom) hide)
    )
    (property "Current" "1A" (at 162.56 254 0)
      (effects (font (size 1.27 1.27) (thickness 0.15)) (justify left bottom) hide)
    )
    (property "Public" "False" (at 162.56 254 0)
      (effects (font (size 1.27 1.27)) (justify left bottom) hide)
    )
    (property "DNP" "DNP" (at 0 0 0)
      (effects (font (size 1 1)))
    )
    (pin "1")
    (pin "2")
    (instances
      (project "ecp5-dc-scm"
        (path ""
          (reference "R133") (unit 1)
        )
      )
    )
  )

  (symbol (lib_id "antmicroResistors0402:R_0R_0402") (at 142.24 226.06 0) (unit 1)
    (in_bom no) (on_board yes) (dnp yes)
    (property "Reference" "R134" (at 139.192 222.504 0)
      (effects (font (size 1.524 1.524)))
    )
    (property "Value" "R_0R_0402" (at 142.24 229.87 0)
      (effects (font (size 1.524 1.524)) hide)
    )
    (property "Footprint" "antmicro-footprints:R_0402_1005Metric" (at 147.32 220.98 0)
      (effects (font (size 1.524 1.524)) (justify left) hide)
    )
    (property "Datasheet" "https://industrial.panasonic.com/cdbs/www-data/pdf/RDA0000/AOA0000C301.pdf" (at 142.24 226.06 0)
      (effects (font (size 1.27 1.27)) hide)
    )
    (property "Manufacturer" "Panasonic" (at 147.32 215.9 0)
      (effects (font (size 1.524 1.524)) (justify left) hide)
    )
    (property "MPN" "ERJ2GE0R00X" (at 147.32 218.44 0)
      (effects (font (size 1.524 1.524)) (justify left) hide)
    )
    (property "Val" "0R" (at 149.098 222.758 0)
      (effects (font (size 1.27 1.27)))
    )
    (property "License" "Apache-2.0" (at 162.56 251.46 0)
      (effects (font (size 1.27 1.27) (thickness 0.15)) (justify left bottom) hide)
    )
    (property "Author" "Antmicro" (at 162.56 254 0)
      (effects (font (size 1.27 1.27) (thickness 0.15)) (justify left bottom) hide)
    )
    (property "Tolerance" "~" (at 162.56 236.22 0)
      (effects (font (size 1.27 1.27)) (justify left bottom) hide)
    )
    (property "Current" "1A" (at 162.56 256.54 0)
      (effects (font (size 1.27 1.27) (thickness 0.15)) (justify left bottom) hide)
    )
    (property "Public" "False" (at 162.56 256.54 0)
      (effects (font (size 1.27 1.27)) (justify left bottom) hide)
    )
    (property "DNP" "DNP" (at 0 0 0)
      (effects (font (size 1 1)))
    )
    (pin "1")
    (pin "2")
    (instances
      (project "ecp5-dc-scm"
        (path ""
          (reference "R134") (unit 1)
        )
      )
    )
  )

  (symbol (lib_id "antmicroResistors0402:R_0R_0402") (at 142.24 220.98 0) (unit 1)
    (in_bom no) (on_board yes) (dnp yes)
    (property "Reference" "R135" (at 139.192 219.964 0)
      (effects (font (size 1.524 1.524)))
    )
    (property "Value" "R_0R_0402" (at 142.24 224.79 0)
      (effects (font (size 1.524 1.524)) hide)
    )
    (property "Footprint" "antmicro-footprints:R_0402_1005Metric" (at 147.32 215.9 0)
      (effects (font (size 1.524 1.524)) (justify left) hide)
    )
    (property "Datasheet" "https://industrial.panasonic.com/cdbs/www-data/pdf/RDA0000/AOA0000C301.pdf" (at 142.24 220.98 0)
      (effects (font (size 1.27 1.27)) hide)
    )
    (property "Manufacturer" "Panasonic" (at 147.32 210.82 0)
      (effects (font (size 1.524 1.524)) (justify left) hide)
    )
    (property "MPN" "ERJ2GE0R00X" (at 147.32 213.36 0)
      (effects (font (size 1.524 1.524)) (justify left) hide)
    )
    (property "Val" "0R" (at 149.098 220.218 0)
      (effects (font (size 1.27 1.27)))
    )
    (property "License" "Apache-2.0" (at 162.56 246.38 0)
      (effects (font (size 1.27 1.27) (thickness 0.15)) (justify left bottom) hide)
    )
    (property "Author" "Antmicro" (at 162.56 248.92 0)
      (effects (font (size 1.27 1.27) (thickness 0.15)) (justify left bottom) hide)
    )
    (property "Tolerance" "~" (at 162.56 231.14 0)
      (effects (font (size 1.27 1.27)) (justify left bottom) hide)
    )
    (property "Current" "1A" (at 162.56 251.46 0)
      (effects (font (size 1.27 1.27) (thickness 0.15)) (justify left bottom) hide)
    )
    (property "Public" "False" (at 162.56 251.46 0)
      (effects (font (size 1.27 1.27)) (justify left bottom) hide)
    )
    (property "DNP" "DNP" (at 0 0 0)
      (effects (font (size 1 1)))
    )
    (pin "1")
    (pin "2")
    (instances
      (project "ecp5-dc-scm"
        (path ""
          (reference "R135") (unit 1)
        )
      )
    )
  )

  (symbol (lib_id "antmicroOscillators:Oscillator_100MHz_ECS_3225MV") (at 372.11 232.41 0) (unit 1)
    (in_bom yes) (on_board yes) (dnp no) (fields_autoplaced)
    (property "Reference" "Y1" (at 381.635 222.25 0)
      (effects (font (size 1.27 1.27) (thickness 0.15)))
    )
    (property "Value" "Oscillator_100MHz_ECS_3225MV" (at 403.86 238.76 0)
      (effects (font (size 1.27 1.27) (thickness 0.15)) (justify left bottom) hide)
    )
    (property "Footprint" "antmicro-footprints:Oscillator_SMD_ECS_3225MV_3.2x2.5x1.2mm" (at 403.86 241.3 0)
      (effects (font (size 1.27 1.27) (thickness 0.15)) (justify left bottom) hide)
    )
    (property "Datasheet" "https://www.mouser.com/datasheet/2/122/ECS_3225MVQ-1825332.pdf" (at 403.86 243.84 0)
      (effects (font (size 1.27 1.27) (thickness 0.15)) (justify left bottom) hide)
    )
    (property "MPN" "ECS-3225MVQ-1000CN-TR" (at 381.635 224.79 0)
      (effects (font (size 1.27 1.27)))
    )
    (property "Manufacturer" "ECS Inc. International" (at 403.86 256.54 0)
      (effects (font (size 1.27 1.27)) (justify left) hide)
    )
    (property "Val" "100 MHz" (at 381.635 227.33 0)
      (effects (font (size 1.27 1.27)))
    )
    (property "License" "Apache-2.0" (at 403.86 251.46 0)
      (effects (font (size 1.27 1.27)) (justify left) hide)
    )
    (property "Author" "Antmicro" (at 403.86 248.92 0)
      (effects (font (size 1.27 1.27)) (justify left) hide)
    )
    (property "Public" "False" (at 403.86 256.54 0)
      (effects (font (size 1.27 1.27)) (justify left bottom) hide)
    )
    (pin "1")
    (pin "3")
    (pin "4")
    (pin "2")
    (instances
      (project "ecp5-dc-scm"
        (path ""
          (reference "Y1") (unit 1)
        )
      )
    )
  )

  (symbol (lib_name "LED_G_0603_LG_L29K-G2J1-24-Z_1") (lib_id "antmicroLEDIndicationDiscrete:LED_G_0603_LG_L29K-G2J1-24-Z") (at 27.94 261.62 270) (mirror x) (unit 1)
    (in_bom yes) (on_board yes) (dnp no)
    (property "Reference" "D14" (at 33.655 257.81 90)
      (effects (font (size 1.27 1.27) (thickness 0.15)))
    )
    (property "Value" "LED_G_0603_LG_L29K-G2J1-24-Z" (at 20.32 241.3 0)
      (effects (font (size 1.27 1.27) (thickness 0.15)) (justify left bottom) hide)
    )
    (property "Footprint" "antmicro-footprints:LED_0603_1608Metric_G" (at 17.78 241.3 0)
      (effects (font (size 1.27 1.27) (thickness 0.15)) (justify left bottom) hide)
    )
    (property "Datasheet" "https://look.ams-osram.com/m/19ee86b3ae0ee95b/original/LG-L29K.pdf" (at 15.24 241.3 0)
      (effects (font (size 1.27 1.27) (thickness 0.15)) (justify left bottom) hide)
    )
    (property "MPN" "LG L29K-G2J1-24-Z" (at 12.7 241.3 0)
      (effects (font (size 1.27 1.27) (thickness 0.15)) (justify left bottom) hide)
    )
    (property "Manufacturer" "OSRAM" (at 10.16 241.3 0)
      (effects (font (size 1.27 1.27) (thickness 0.15)) (justify left bottom) hide)
    )
    (property "Color" "Green" (at 34.29 260.35 90)
      (effects (font (size 1.27 1.27)))
    )
    (property "Author" "Antmicro" (at 7.62 241.3 0)
      (effects (font (size 1.27 1.27) (thickness 0.15)) (justify left bottom) hide)
    )
    (property "License" "Apache-2.0" (at 5.08 241.3 0)
      (effects (font (size 1.27 1.27) (thickness 0.15)) (justify left bottom) hide)
    )
    (pin "1")
    (pin "2")
    (instances
      (project "ecp5-dc-scm"
        (path ""
          (reference "D14") (unit 1)
        )
      )
    )
  )

  (symbol (lib_name "SW_B3U-1000P_SMD_1") (lib_id "antmicroPushbuttonSwitches:SW_B3U-1000P_SMD") (at 52.07 265.43 270) (unit 1)
    (in_bom yes) (on_board yes) (dnp no) (fields_autoplaced)
    (property "Reference" "SW1" (at 55.88 269.24 90)
      (effects (font (size 1.27 1.27) (thickness 0.15)) (justify left))
    )
    (property "Value" "SW_B3U-1000P_SMD" (at 46.99 290.83 0)
      (effects (font (size 1.27 1.27) (thickness 0.15)) (justify left bottom) hide)
    )
    (property "Footprint" "antmicro-footprints:SW_B3U-1000P_SMD" (at 44.45 290.83 0)
      (effects (font (size 1.27 1.27) (thickness 0.15)) (justify left bottom) hide)
    )
    (property "Datasheet" "https://omronfs.omron.com/en_US/ecb/products/pdf/en-b3u.pdf" (at 41.91 290.83 0)
      (effects (font (size 1.27 1.27) (thickness 0.15)) (justify left bottom) hide)
    )
    (property "MPN" "B3U-1000P" (at 55.88 271.78 90)
      (effects (font (size 1.27 1.27) (thickness 0.15)) (justify left))
    )
    (property "Manufacturer" "Omron" (at 36.83 290.83 0)
      (effects (font (size 1.27 1.27) (thickness 0.15)) (justify left bottom) hide)
    )
    (property "Author" "Antmicro" (at 34.29 290.83 0)
      (effects (font (size 1.27 1.27) (thickness 0.15)) (justify left bottom) hide)
    )
    (property "License" "Apache-2.0" (at 31.75 290.83 0)
      (effects (font (size 1.27 1.27) (thickness 0.15)) (justify left bottom) hide)
    )
    (pin "2")
    (pin "1")
    (instances
      (project "ecp5-dc-scm"
        (path ""
          (reference "SW1") (unit 1)
        )
      )
    )
  )

  (symbol (lib_name "LED_G_0603_LG_L29K-G2J1-24-Z_1") (lib_id "antmicroLEDIndicationDiscrete:LED_G_0603_LG_L29K-G2J1-24-Z") (at 41.91 222.25 270) (mirror x) (unit 1)
    (in_bom yes) (on_board yes) (dnp no)
    (property "Reference" "D15" (at 47.625 218.44 90)
      (effects (font (size 1.27 1.27) (thickness 0.15)))
    )
    (property "Value" "LED_G_0603_LG_L29K-G2J1-24-Z" (at 34.29 201.93 0)
      (effects (font (size 1.27 1.27) (thickness 0.15)) (justify left bottom) hide)
    )
    (property "Footprint" "antmicro-footprints:LED_0603_1608Metric_G" (at 31.75 201.93 0)
      (effects (font (size 1.27 1.27) (thickness 0.15)) (justify left bottom) hide)
    )
    (property "Datasheet" "https://look.ams-osram.com/m/19ee86b3ae0ee95b/original/LG-L29K.pdf" (at 29.21 201.93 0)
      (effects (font (size 1.27 1.27) (thickness 0.15)) (justify left bottom) hide)
    )
    (property "MPN" "LG L29K-G2J1-24-Z" (at 26.67 201.93 0)
      (effects (font (size 1.27 1.27) (thickness 0.15)) (justify left bottom) hide)
    )
    (property "Manufacturer" "OSRAM" (at 24.13 201.93 0)
      (effects (font (size 1.27 1.27) (thickness 0.15)) (justify left bottom) hide)
    )
    (property "Color" "Green" (at 48.26 220.98 90)
      (effects (font (size 1.27 1.27)))
    )
    (property "Author" "Antmicro" (at 21.59 201.93 0)
      (effects (font (size 1.27 1.27) (thickness 0.15)) (justify left bottom) hide)
    )
    (property "License" "Apache-2.0" (at 19.05 201.93 0)
      (effects (font (size 1.27 1.27) (thickness 0.15)) (justify left bottom) hide)
    )
    (pin "1")
    (pin "2")
    (instances
      (project "ecp5-dc-scm"
        (path ""
          (reference "D15") (unit 1)
        )
      )
    )
  )
)
